G04 ================== begin FILE IDENTIFICATION RECORD ==================*
G04 Layout Name:  D:/<user>/Wistron_project/16347-sc/gbr/16347-sc.brd*
G04 Film Name:    SE_REF_L2*
G04 File Format:  Gerber RS274X*
G04 File Origin:  Cadence Allegro 16.5-S056*
G04 Origin Date:  Tue Mar 14 17:08:24 2017*
G04 *
G04 Layer:  BOARD GEOMETRY/SE_REF_L2_TBL*
G04 Layer:  BOARD GEOMETRY/SE_REF_L2_BOTTOM*
G04 Layer:  BOARD GEOMETRY/PANEL_OUTLINE*
G04 *
G04 Offset:    (0.00 0.00)*
G04 Mirror:    No*
G04 Mode:      Positive*
G04 Rotation:  0*
G04 FullContactRelief:  No*
G04 UndefLineWidth:     6.00*
G04 ================== end FILE IDENTIFICATION RECORD ====================*
%FSLAX35Y35*MOIN*%
%IR0*IPPOS*OFA0.00000B0.00000*MIA0B0*SFA1.00000B1.00000*%
%ADD10C,.02*%
%ADD11C,.006*%
G75*
%LPD*%
G75*
G54D10*
G01X84600Y12000D02*
X83925Y12675D01*
G01D02*
Y17550D01*
G01X88350Y11800D02*
X84800D01*
G01D02*
X84600Y12000D01*
G01X69825Y17550D02*
Y12575D01*
G01D02*
X70800Y11600D01*
G01D02*
X71000D01*
G01X74450Y11400D02*
X71200D01*
G01D02*
X71000Y11600D01*
G01X124500Y12100D02*
X122225Y14375D01*
G01D02*
Y16150D01*
G01X127750Y10400D02*
X126200D01*
G01D02*
X124500Y12100D01*
G01X111100Y10400D02*
X108125Y13375D01*
G01D02*
Y16150D01*
G01X114950Y10400D02*
X111100D01*
G01X265042Y13093D02*
Y18214D01*
G01D02*
X265332Y18504D01*
G01X268472Y12786D02*
X265349D01*
G01D02*
X265042Y13093D01*
G01X251232Y18504D02*
X249679Y16951D01*
G01D02*
Y13029D01*
G01D02*
X249762Y12946D01*
G01X252961Y12770D02*
X249939D01*
G01D02*
X249763Y12946D01*
G01D02*
X249762D01*
G01X415025Y19550D02*
X414700Y19225D01*
G01D02*
Y13800D01*
G01X418050D02*
X414700D01*
G01X428600D02*
Y18925D01*
G01D02*
X429225Y19550D01*
G01X432150Y13800D02*
X428600D01*
G01X647600Y12500D02*
Y18025D01*
G01D02*
X647825Y18250D01*
G01X651650Y12500D02*
X647600D01*
G01X851285Y827061D02*
X1568785D01*
G01X851285Y896361D02*
Y827061D01*
G01Y861711D02*
X1568785D01*
G01X851285Y896361D02*
X1568785D01*
G01X1026285D02*
Y827061D01*
G01X1253785Y896361D02*
Y827061D01*
G01X1358785Y896361D02*
Y827061D01*
G01X1568785Y896361D02*
Y827061D01*
G54D11*
G01X6250Y-36737D02*
Y-54237D01*
G01X1228Y-36737D02*
X11272D01*
G01X20038Y-54237D02*
Y-36737D01*
G01Y-45195D02*
X21130Y-43737D01*
X22222Y-42862D01*
X23968Y-42571D01*
X25278Y-42862D01*
X26807Y-44029D01*
X27462Y-45779D01*
Y-54237D01*
G01X41250Y-42571D02*
Y-54237D01*
G01Y-37904D02*
X40813Y-37612D01*
Y-37029D01*
X41250Y-36737D01*
X41687Y-37029D01*
Y-37612D01*
X41250Y-37904D01*
G01X55475Y-52196D02*
X56567Y-53362D01*
X58095Y-54237D01*
X59405D01*
X60715Y-53654D01*
X61588Y-52779D01*
X62025Y-51613D01*
X61807Y-49862D01*
X60933Y-48987D01*
X57003Y-47237D01*
X56130Y-45195D01*
X56567Y-43737D01*
X57440Y-42862D01*
X58750Y-42571D01*
X60060Y-42862D01*
X61370Y-43737D01*
G01X90693Y-58612D02*
X92222Y-59779D01*
X93968Y-60070D01*
X95496Y-59779D01*
X96807Y-58321D01*
X97680Y-56279D01*
Y-42571D01*
G01Y-44904D02*
X96807Y-43737D01*
X95496Y-42862D01*
X93968Y-42571D01*
X92222Y-43154D01*
X91130Y-44320D01*
X90256Y-46362D01*
X89820Y-48404D01*
X90038Y-50154D01*
X90912Y-52196D01*
X92222Y-53654D01*
X93968Y-54237D01*
X95278Y-53945D01*
X96807Y-52779D01*
X97680Y-51613D01*
G01X107975Y-46362D02*
X114962D01*
X114307Y-44320D01*
X113215Y-43154D01*
X111687Y-42571D01*
X110158Y-42862D01*
X108848Y-43737D01*
X107975Y-45779D01*
X107538Y-47529D01*
Y-49279D01*
X107975Y-51029D01*
X109067Y-52779D01*
X110377Y-53945D01*
X111905Y-54237D01*
X113433Y-53654D01*
X114962Y-51904D01*
G01X125693Y-54237D02*
Y-42571D01*
G01Y-44904D02*
X126785Y-43737D01*
X127877Y-42862D01*
X129405Y-42571D01*
X130496Y-42862D01*
X131807Y-43737D01*
G01X142320Y-54237D02*
Y-36737D01*
G01Y-45487D02*
X143412Y-43737D01*
X144722Y-42862D01*
X146032Y-42571D01*
X147996Y-43154D01*
X149307Y-44320D01*
X150180Y-46362D01*
Y-48695D01*
X149743Y-51029D01*
X148870Y-52779D01*
X147342Y-53945D01*
X146032Y-54237D01*
X144722Y-53945D01*
X143412Y-53071D01*
X142320Y-51613D01*
G01X160475Y-46362D02*
X167462D01*
X166807Y-44320D01*
X165715Y-43154D01*
X164187Y-42571D01*
X162658Y-42862D01*
X161348Y-43737D01*
X160475Y-45779D01*
X160038Y-47529D01*
Y-49279D01*
X160475Y-51029D01*
X161567Y-52779D01*
X162877Y-53945D01*
X164405Y-54237D01*
X165933Y-53654D01*
X167462Y-51904D01*
G01X178193Y-54237D02*
Y-42571D01*
G01Y-44904D02*
X179285Y-43737D01*
X180377Y-42862D01*
X181905Y-42571D01*
X182996Y-42862D01*
X184307Y-43737D01*
G01X216250Y-42571D02*
Y-54237D01*
G01Y-37904D02*
X215813Y-37612D01*
Y-37029D01*
X216250Y-36737D01*
X216687Y-37029D01*
Y-37612D01*
X216250Y-37904D01*
G01X230475Y-52196D02*
X231567Y-53362D01*
X233095Y-54237D01*
X234405D01*
X235715Y-53654D01*
X236588Y-52779D01*
X237025Y-51613D01*
X236807Y-49862D01*
X235933Y-48987D01*
X232003Y-47237D01*
X231130Y-45195D01*
X231567Y-43737D01*
X232440Y-42862D01*
X233750Y-42571D01*
X235060Y-42862D01*
X236370Y-43737D01*
G01X265256Y-58612D02*
X266785Y-59779D01*
X268095Y-60070D01*
X269842Y-59487D01*
X271152Y-58029D01*
X271807Y-55403D01*
Y-42571D01*
G01Y-37904D02*
X271370Y-37612D01*
Y-37029D01*
X271807Y-36737D01*
X272243Y-37029D01*
Y-37612D01*
X271807Y-37904D01*
G01X282538Y-42571D02*
Y-50737D01*
X283412Y-52779D01*
X284722Y-53945D01*
X286250Y-54237D01*
X287778Y-53945D01*
X289088Y-52779D01*
X289962Y-50737D01*
G01Y-54237D02*
Y-42571D01*
G01X300475Y-52196D02*
X301567Y-53362D01*
X303095Y-54237D01*
X304405D01*
X305715Y-53654D01*
X306588Y-52779D01*
X307025Y-51613D01*
X306807Y-49862D01*
X305933Y-48987D01*
X302003Y-47237D01*
X301130Y-45195D01*
X301567Y-43737D01*
X302440Y-42862D01*
X303750Y-42571D01*
X305060Y-42862D01*
X306370Y-43737D01*
G01X321250Y-36737D02*
Y-54237D01*
G01X318193Y-42571D02*
X324307D01*
G01X354940Y-54237D02*
Y-39362D01*
X355377Y-37904D01*
X356250Y-37029D01*
X357560Y-36737D01*
X358870Y-37320D01*
X359525Y-38779D01*
G01X356905Y-43737D02*
X352538D01*
G01X373750Y-54237D02*
X372440Y-53945D01*
X371130Y-52779D01*
X370256Y-50737D01*
X369820Y-48404D01*
X370256Y-46070D01*
X371130Y-44029D01*
X372440Y-42862D01*
X373750Y-42571D01*
X375060Y-42862D01*
X376370Y-44029D01*
X377243Y-46070D01*
X377462Y-48404D01*
X377243Y-50737D01*
X376370Y-52779D01*
X375060Y-53945D01*
X373750Y-54237D01*
G01X388193D02*
Y-42571D01*
G01Y-44904D02*
X389285Y-43737D01*
X390377Y-42862D01*
X391905Y-42571D01*
X392996Y-42862D01*
X394307Y-43737D01*
G01X421665Y-59487D02*
X422975Y-60070D01*
X424722Y-59487D01*
X425813Y-58321D01*
X426687Y-56862D01*
X427996Y-52196D01*
X430835Y-42571D01*
G01X423848D02*
X427996Y-52196D01*
G01X443750Y-54237D02*
X442440Y-53945D01*
X441130Y-52779D01*
X440256Y-50737D01*
X439820Y-48404D01*
X440256Y-46070D01*
X441130Y-44029D01*
X442440Y-42862D01*
X443750Y-42571D01*
X445060Y-42862D01*
X446370Y-44029D01*
X447243Y-46070D01*
X447462Y-48404D01*
X447243Y-50737D01*
X446370Y-52779D01*
X445060Y-53945D01*
X443750Y-54237D01*
G01X457538Y-42571D02*
Y-50737D01*
X458412Y-52779D01*
X459722Y-53945D01*
X461250Y-54237D01*
X462778Y-53945D01*
X464088Y-52779D01*
X464962Y-50737D01*
G01Y-54237D02*
Y-42571D01*
G01X475693Y-54237D02*
Y-42571D01*
G01Y-44904D02*
X476785Y-43737D01*
X477877Y-42862D01*
X479405Y-42571D01*
X480496Y-42862D01*
X481807Y-43737D01*
G01X510693Y-54237D02*
Y-42571D01*
G01Y-44904D02*
X511785Y-43737D01*
X512877Y-42862D01*
X514405Y-42571D01*
X515496Y-42862D01*
X516807Y-43737D01*
G01X527975Y-46362D02*
X534962D01*
X534307Y-44320D01*
X533215Y-43154D01*
X531687Y-42571D01*
X530158Y-42862D01*
X528848Y-43737D01*
X527975Y-45779D01*
X527538Y-47529D01*
Y-49279D01*
X527975Y-51029D01*
X529067Y-52779D01*
X530377Y-53945D01*
X531905Y-54237D01*
X533433Y-53654D01*
X534962Y-51904D01*
G01X547440Y-54237D02*
Y-39362D01*
X547877Y-37904D01*
X548750Y-37029D01*
X550060Y-36737D01*
X551370Y-37320D01*
X552025Y-38779D01*
G01X549405Y-43737D02*
X545038D01*
G01X562975Y-46362D02*
X569962D01*
X569307Y-44320D01*
X568215Y-43154D01*
X566687Y-42571D01*
X565158Y-42862D01*
X563848Y-43737D01*
X562975Y-45779D01*
X562538Y-47529D01*
Y-49279D01*
X562975Y-51029D01*
X564067Y-52779D01*
X565377Y-53945D01*
X566905Y-54237D01*
X568433Y-53654D01*
X569962Y-51904D01*
G01X580693Y-54237D02*
Y-42571D01*
G01Y-44904D02*
X581785Y-43737D01*
X582877Y-42862D01*
X584405Y-42571D01*
X585496Y-42862D01*
X586807Y-43737D01*
G01X597975Y-46362D02*
X604962D01*
X604307Y-44320D01*
X603215Y-43154D01*
X601687Y-42571D01*
X600158Y-42862D01*
X598848Y-43737D01*
X597975Y-45779D01*
X597538Y-47529D01*
Y-49279D01*
X597975Y-51029D01*
X599067Y-52779D01*
X600377Y-53945D01*
X601905Y-54237D01*
X603433Y-53654D01*
X604962Y-51904D01*
G01X615038Y-54237D02*
Y-42571D01*
G01Y-45487D02*
X615912Y-44029D01*
X617222Y-42862D01*
X618968Y-42571D01*
X620496Y-42862D01*
X621807Y-44029D01*
X622462Y-46070D01*
Y-54237D01*
G01X639743Y-44029D02*
X638215Y-42862D01*
X636905Y-42571D01*
X635158Y-43154D01*
X633848Y-44320D01*
X632975Y-46362D01*
X632756Y-48404D01*
X632975Y-50446D01*
X633848Y-52196D01*
X635158Y-53654D01*
X636905Y-54237D01*
X638433Y-53654D01*
X639743Y-52487D01*
G01X650475Y-46362D02*
X657462D01*
X656807Y-44320D01*
X655715Y-43154D01*
X654187Y-42571D01*
X652658Y-42862D01*
X651348Y-43737D01*
X650475Y-45779D01*
X650038Y-47529D01*
Y-49279D01*
X650475Y-51029D01*
X651567Y-52779D01*
X652877Y-53945D01*
X654405Y-54237D01*
X655933Y-53654D01*
X657462Y-51904D01*
G01X688750Y-36737D02*
Y-54237D01*
G01X685693Y-42571D02*
X691807D01*
G01X706250Y-54237D02*
X704940Y-53945D01*
X703630Y-52779D01*
X702756Y-50737D01*
X702320Y-48404D01*
X702756Y-46070D01*
X703630Y-44029D01*
X704940Y-42862D01*
X706250Y-42571D01*
X707560Y-42862D01*
X708870Y-44029D01*
X709743Y-46070D01*
X709962Y-48404D01*
X709743Y-50737D01*
X708870Y-52779D01*
X707560Y-53945D01*
X706250Y-54237D01*
G01X739940D02*
Y-39362D01*
X740377Y-37904D01*
X741250Y-37029D01*
X742560Y-36737D01*
X743870Y-37320D01*
X744525Y-38779D01*
G01X741905Y-43737D02*
X737538D01*
G01X758750Y-42571D02*
Y-54237D01*
G01Y-37904D02*
X758313Y-37612D01*
Y-37029D01*
X758750Y-36737D01*
X759187Y-37029D01*
Y-37612D01*
X758750Y-37904D01*
G01X772538Y-54237D02*
Y-42571D01*
G01Y-45487D02*
X773412Y-44029D01*
X774722Y-42862D01*
X776468Y-42571D01*
X777996Y-42862D01*
X779307Y-44029D01*
X779962Y-46070D01*
Y-54237D01*
G01X797680Y-36737D02*
Y-54237D01*
G01Y-51613D02*
X796807Y-53071D01*
X795496Y-53945D01*
X793968Y-54237D01*
X792222Y-53654D01*
X790912Y-52196D01*
X790038Y-50446D01*
X789820Y-48404D01*
X790038Y-46362D01*
X790912Y-44612D01*
X792222Y-43154D01*
X793968Y-42571D01*
X795496Y-42862D01*
X796588Y-43446D01*
X797680Y-44612D01*
G01X828750Y-36737D02*
Y-54237D01*
G01X825693Y-42571D02*
X831807D01*
G01X842538Y-54237D02*
Y-36737D01*
G01Y-45195D02*
X843630Y-43737D01*
X844722Y-42862D01*
X846468Y-42571D01*
X847778Y-42862D01*
X849307Y-44029D01*
X849962Y-45779D01*
Y-54237D01*
G01X860475Y-46362D02*
X867462D01*
X866807Y-44320D01*
X865715Y-43154D01*
X864187Y-42571D01*
X862658Y-42862D01*
X861348Y-43737D01*
X860475Y-45779D01*
X860038Y-47529D01*
Y-49279D01*
X860475Y-51029D01*
X861567Y-52779D01*
X862877Y-53945D01*
X864405Y-54237D01*
X865933Y-53654D01*
X867462Y-51904D01*
G01X894165D02*
X895912Y-53362D01*
X897877Y-54237D01*
X899623D01*
X901370Y-53362D01*
X902680Y-51904D01*
X903335Y-49862D01*
X902898Y-47821D01*
X901807Y-46070D01*
X899842Y-44904D01*
X897222Y-44320D01*
X895693Y-43154D01*
X895038Y-41112D01*
X895475Y-39070D01*
X896567Y-37612D01*
X898095Y-36737D01*
X899623D01*
X901152Y-37320D01*
X902462Y-38779D01*
G01X920617Y-54237D02*
X911883D01*
Y-36737D01*
X920617D01*
G01X917123Y-45195D02*
X911883D01*
G01X951250Y-42571D02*
Y-54237D01*
G01Y-37904D02*
X950813Y-37612D01*
Y-37029D01*
X951250Y-36737D01*
X951687Y-37029D01*
Y-37612D01*
X951250Y-37904D01*
G01X962200Y-54237D02*
Y-42571D01*
G01Y-45779D02*
X962855Y-44320D01*
X963947Y-43154D01*
X965475Y-42571D01*
X967003Y-43154D01*
X968095Y-44320D01*
X968750Y-45779D01*
Y-54237D01*
G01Y-45779D02*
X969405Y-44320D01*
X970496Y-43154D01*
X972025Y-42571D01*
X973553Y-43154D01*
X974645Y-44320D01*
X975300Y-46070D01*
Y-54237D01*
G01X982320Y-60070D02*
Y-42571D01*
G01Y-45195D02*
X983412Y-43737D01*
X984503Y-42862D01*
X986250Y-42571D01*
X987778Y-42862D01*
X989307Y-44320D01*
X989962Y-46362D01*
X990180Y-48404D01*
X989962Y-50446D01*
X989307Y-52487D01*
X987996Y-53654D01*
X986250Y-54237D01*
X984722Y-53945D01*
X983193Y-53071D01*
X982320Y-51904D01*
G01X1000475Y-46362D02*
X1007462D01*
X1006807Y-44320D01*
X1005715Y-43154D01*
X1004187Y-42571D01*
X1002658Y-42862D01*
X1001348Y-43737D01*
X1000475Y-45779D01*
X1000038Y-47529D01*
Y-49279D01*
X1000475Y-51029D01*
X1001567Y-52779D01*
X1002877Y-53945D01*
X1004405Y-54237D01*
X1005933Y-53654D01*
X1007462Y-51904D01*
G01X1025180Y-36737D02*
Y-54237D01*
G01Y-51613D02*
X1024307Y-53071D01*
X1022996Y-53945D01*
X1021468Y-54237D01*
X1019722Y-53654D01*
X1018412Y-52196D01*
X1017538Y-50446D01*
X1017320Y-48404D01*
X1017538Y-46362D01*
X1018412Y-44612D01*
X1019722Y-43154D01*
X1021468Y-42571D01*
X1022996Y-42862D01*
X1024088Y-43446D01*
X1025180Y-44612D01*
G01X1042680Y-54237D02*
Y-42571D01*
G01Y-44612D02*
X1041807Y-43446D01*
X1040496Y-42862D01*
X1038968Y-42571D01*
X1037440Y-43154D01*
X1036130Y-44320D01*
X1035256Y-46070D01*
X1034820Y-48404D01*
X1035256Y-50737D01*
X1036130Y-52487D01*
X1037440Y-53654D01*
X1038968Y-54237D01*
X1040496Y-53945D01*
X1041807Y-53071D01*
X1042680Y-51904D01*
G01X1052538Y-54237D02*
Y-42571D01*
G01Y-45487D02*
X1053412Y-44029D01*
X1054722Y-42862D01*
X1056468Y-42571D01*
X1057996Y-42862D01*
X1059307Y-44029D01*
X1059962Y-46070D01*
Y-54237D01*
G01X1077243Y-44029D02*
X1075715Y-42862D01*
X1074405Y-42571D01*
X1072658Y-43154D01*
X1071348Y-44320D01*
X1070475Y-46362D01*
X1070256Y-48404D01*
X1070475Y-50446D01*
X1071348Y-52196D01*
X1072658Y-53654D01*
X1074405Y-54237D01*
X1075933Y-53654D01*
X1077243Y-52487D01*
G01X1087975Y-46362D02*
X1094962D01*
X1094307Y-44320D01*
X1093215Y-43154D01*
X1091687Y-42571D01*
X1090158Y-42862D01*
X1088848Y-43737D01*
X1087975Y-45779D01*
X1087538Y-47529D01*
Y-49279D01*
X1087975Y-51029D01*
X1089067Y-52779D01*
X1090377Y-53945D01*
X1091905Y-54237D01*
X1093433Y-53654D01*
X1094962Y-51904D01*
G01X1126250Y-36737D02*
Y-54237D01*
G01X1123193Y-42571D02*
X1129307D01*
G01X1140693Y-54237D02*
Y-42571D01*
G01Y-44904D02*
X1141785Y-43737D01*
X1142877Y-42862D01*
X1144405Y-42571D01*
X1145496Y-42862D01*
X1146807Y-43737D01*
G01X1165180Y-54237D02*
Y-42571D01*
G01Y-44612D02*
X1164307Y-43446D01*
X1162996Y-42862D01*
X1161468Y-42571D01*
X1159940Y-43154D01*
X1158630Y-44320D01*
X1157756Y-46070D01*
X1157320Y-48404D01*
X1157756Y-50737D01*
X1158630Y-52487D01*
X1159940Y-53654D01*
X1161468Y-54237D01*
X1162996Y-53945D01*
X1164307Y-53071D01*
X1165180Y-51904D01*
G01X1182243Y-44029D02*
X1180715Y-42862D01*
X1179405Y-42571D01*
X1177658Y-43154D01*
X1176348Y-44320D01*
X1175475Y-46362D01*
X1175256Y-48404D01*
X1175475Y-50446D01*
X1176348Y-52196D01*
X1177658Y-53654D01*
X1179405Y-54237D01*
X1180933Y-53654D01*
X1182243Y-52487D01*
G01X1192975Y-46362D02*
X1199962D01*
X1199307Y-44320D01*
X1198215Y-43154D01*
X1196687Y-42571D01*
X1195158Y-42862D01*
X1193848Y-43737D01*
X1192975Y-45779D01*
X1192538Y-47529D01*
Y-49279D01*
X1192975Y-51029D01*
X1194067Y-52779D01*
X1195377Y-53945D01*
X1196905Y-54237D01*
X1198433Y-53654D01*
X1199962Y-51904D01*
G01X1210475Y-52196D02*
X1211567Y-53362D01*
X1213095Y-54237D01*
X1214405D01*
X1215715Y-53654D01*
X1216588Y-52779D01*
X1217025Y-51613D01*
X1216807Y-49862D01*
X1215933Y-48987D01*
X1212003Y-47237D01*
X1211130Y-45195D01*
X1211567Y-43737D01*
X1212440Y-42862D01*
X1213750Y-42571D01*
X1215060Y-42862D01*
X1216370Y-43737D01*
G01X1248750Y-42571D02*
Y-54237D01*
G01Y-37904D02*
X1248313Y-37612D01*
Y-37029D01*
X1248750Y-36737D01*
X1249187Y-37029D01*
Y-37612D01*
X1248750Y-37904D01*
G01X1262538Y-54237D02*
Y-42571D01*
G01Y-45487D02*
X1263412Y-44029D01*
X1264722Y-42862D01*
X1266468Y-42571D01*
X1267996Y-42862D01*
X1269307Y-44029D01*
X1269962Y-46070D01*
Y-54237D01*
G01X1301250D02*
Y-36737D01*
G01X1322680Y-54237D02*
Y-42571D01*
G01Y-44612D02*
X1321807Y-43446D01*
X1320496Y-42862D01*
X1318968Y-42571D01*
X1317440Y-43154D01*
X1316130Y-44320D01*
X1315256Y-46070D01*
X1314820Y-48404D01*
X1315256Y-50737D01*
X1316130Y-52487D01*
X1317440Y-53654D01*
X1318968Y-54237D01*
X1320496Y-53945D01*
X1321807Y-53071D01*
X1322680Y-51904D01*
G01X1331665Y-59487D02*
X1332975Y-60070D01*
X1334722Y-59487D01*
X1335813Y-58321D01*
X1336687Y-56862D01*
X1337996Y-52196D01*
X1340835Y-42571D01*
G01X1333848D02*
X1337996Y-52196D01*
G01X1350475Y-46362D02*
X1357462D01*
X1356807Y-44320D01*
X1355715Y-43154D01*
X1354187Y-42571D01*
X1352658Y-42862D01*
X1351348Y-43737D01*
X1350475Y-45779D01*
X1350038Y-47529D01*
Y-49279D01*
X1350475Y-51029D01*
X1351567Y-52779D01*
X1352877Y-53945D01*
X1354405Y-54237D01*
X1355933Y-53654D01*
X1357462Y-51904D01*
G01X1368193Y-54237D02*
Y-42571D01*
G01Y-44904D02*
X1369285Y-43737D01*
X1370377Y-42862D01*
X1371905Y-42571D01*
X1372996Y-42862D01*
X1374307Y-43737D01*
G01X1401883Y-36737D02*
Y-54237D01*
X1410617D01*
G01X1419602Y-39654D02*
X1420912Y-37904D01*
X1422440Y-37029D01*
X1424187Y-36737D01*
X1426370Y-37320D01*
X1427898Y-38779D01*
X1428335Y-40528D01*
X1428117Y-42279D01*
X1427243Y-43737D01*
X1422877Y-46654D01*
X1420912Y-48695D01*
X1419602Y-51613D01*
X1419165Y-54237D01*
X1428335D01*
G01X1441250Y-54820D02*
X1440813Y-54529D01*
Y-53945D01*
X1441250Y-53654D01*
X1441687Y-53945D01*
Y-54529D01*
X1441250Y-54820D01*
G01X853250Y908444D02*
X854997Y906986D01*
X856962Y906111D01*
X858708D01*
X860455Y906986D01*
X861765Y908444D01*
X862420Y910486D01*
X861983Y912527D01*
X860892Y914278D01*
X858927Y915444D01*
X856307Y916028D01*
X854778Y917194D01*
X854123Y919236D01*
X854560Y921278D01*
X855652Y922736D01*
X857180Y923611D01*
X858708D01*
X860237Y923028D01*
X861547Y921569D01*
G01X879702Y906111D02*
X870968D01*
Y923611D01*
X879702D01*
G01X876208Y915153D02*
X870968D01*
G01X907715Y923611D02*
X912955D01*
G01X910335D02*
Y906111D01*
G01X907715D02*
X912955D01*
G01X922158D02*
Y923611D01*
X927835Y909028D01*
X933512Y923611D01*
Y906111D01*
G01X940968D02*
Y923611D01*
X946208D01*
X947955Y922736D01*
X949265Y920694D01*
X949702Y918361D01*
X949265Y916028D01*
X948173Y914278D01*
X946208Y913402D01*
X940968D01*
G01X967202Y906111D02*
X958468D01*
Y923611D01*
X967202D01*
G01X963708Y915153D02*
X958468D01*
G01X975532Y906111D02*
Y923611D01*
X979898D01*
X981645Y922736D01*
X982955Y921569D01*
X984047Y919820D01*
X984920Y917777D01*
X985138Y914861D01*
X984920Y911944D01*
X984047Y909902D01*
X982955Y908152D01*
X981645Y906986D01*
X979898Y906111D01*
X975532D01*
G01X992376D02*
X997835Y923611D01*
X1003294Y906111D01*
G01X1001328Y912236D02*
X994341D01*
G01X1010313Y906111D02*
Y923611D01*
X1020357Y906111D01*
Y923611D01*
G01X1037638Y922152D02*
X1036328Y923028D01*
X1034800Y923611D01*
X1033053D01*
X1031088Y922736D01*
X1029560Y921278D01*
X1028468Y919527D01*
X1027595Y916611D01*
X1027376Y913986D01*
X1027813Y911361D01*
X1028468Y909611D01*
X1029778Y907861D01*
X1031307Y906694D01*
X1032835Y906111D01*
X1034363D01*
X1035892Y906694D01*
X1037202Y907569D01*
X1038294Y908735D01*
G01X1054702Y906111D02*
X1045968D01*
Y923611D01*
X1054702D01*
G01X1051208Y915153D02*
X1045968D01*
G01X1085335Y923611D02*
Y906111D01*
G01X1080313Y923611D02*
X1090357D01*
G01X1097376Y906111D02*
X1102835Y923611D01*
X1108294Y906111D01*
G01X1106328Y912236D02*
X1099341D01*
G01X1122081Y915444D02*
X1122955Y916319D01*
X1123610Y917777D01*
X1124047Y919820D01*
X1123610Y921569D01*
X1122737Y922736D01*
X1121208Y923611D01*
X1115313D01*
Y906111D01*
X1122518D01*
X1124047Y907277D01*
X1124920Y909028D01*
X1125357Y911069D01*
X1124920Y913111D01*
X1123610Y914861D01*
X1122081Y915444D01*
X1115313D01*
G01X1133468Y923611D02*
Y906111D01*
X1142202D01*
G01X1159702D02*
X1150968D01*
Y923611D01*
X1159702D01*
G01X1156208Y915153D02*
X1150968D01*
G01X1172835Y905528D02*
X1172398Y905819D01*
Y906403D01*
X1172835Y906694D01*
X1173272Y906403D01*
Y905819D01*
X1172835Y905528D01*
G01Y913402D02*
X1172398Y913694D01*
Y914278D01*
X1172835Y914569D01*
X1173272Y914278D01*
Y913694D01*
X1172835Y913402D01*
G01X1203468Y923611D02*
Y906111D01*
X1212202D01*
G01X1221187Y920694D02*
X1222497Y922444D01*
X1224025Y923319D01*
X1225772Y923611D01*
X1227955Y923028D01*
X1229483Y921569D01*
X1229920Y919820D01*
X1229702Y918069D01*
X1228828Y916611D01*
X1224462Y913694D01*
X1222497Y911653D01*
X1221187Y908735D01*
X1220750Y906111D01*
X1229920D01*
G01X874915Y888961D02*
X880155D01*
G01X877535D02*
Y871461D01*
G01X874915D02*
X880155D01*
G01X889358D02*
Y888961D01*
X895035Y874378D01*
X900712Y888961D01*
Y871461D01*
G01X908168D02*
Y888961D01*
X913408D01*
X915155Y888086D01*
X916465Y886044D01*
X916902Y883711D01*
X916465Y881378D01*
X915373Y879628D01*
X913408Y878752D01*
X908168D01*
G01X928943Y865628D02*
X926760Y868544D01*
X925668Y871461D01*
Y883127D01*
X926760Y886044D01*
X928943Y888961D01*
G01X947535Y871461D02*
X945788Y871753D01*
X944260Y872919D01*
X942950Y874669D01*
X942076Y876711D01*
X941640Y879044D01*
Y881378D01*
X942076Y883711D01*
X942950Y885753D01*
X944260Y887502D01*
X945788Y888669D01*
X947535Y888961D01*
X949281Y888669D01*
X950810Y887502D01*
X952120Y885753D01*
X952994Y883711D01*
X953430Y881378D01*
Y879044D01*
X952994Y876711D01*
X952120Y874669D01*
X950810Y872919D01*
X949281Y871753D01*
X947535Y871461D01*
G01X961323D02*
Y888961D01*
G01Y880503D02*
X962415Y881961D01*
X963507Y882836D01*
X965253Y883127D01*
X966563Y882836D01*
X968092Y881669D01*
X968747Y879919D01*
Y871461D01*
G01X975985D02*
Y883127D01*
G01Y879919D02*
X976640Y881378D01*
X977732Y882544D01*
X979260Y883127D01*
X980788Y882544D01*
X981880Y881378D01*
X982535Y879919D01*
Y871461D01*
G01Y879919D02*
X983190Y881378D01*
X984281Y882544D01*
X985810Y883127D01*
X987338Y882544D01*
X988430Y881378D01*
X989085Y879628D01*
Y871461D01*
G01X1001127Y865628D02*
X1003310Y868544D01*
X1004402Y871461D01*
Y883127D01*
X1003310Y886044D01*
X1001127Y888961D01*
G01X907732Y839435D02*
X909041Y837977D01*
X910570Y837103D01*
X912535Y836811D01*
X914500Y837394D01*
X916028Y838561D01*
X917120Y840602D01*
X917338Y842936D01*
X916902Y845269D01*
X915810Y846728D01*
X914281Y847894D01*
X912753Y848186D01*
X911225Y847894D01*
X909260Y846728D01*
X909915Y854311D01*
X915810D01*
G01X930035D02*
X928288Y853728D01*
X926978Y852269D01*
X926105Y850520D01*
X925450Y848186D01*
X925232Y845561D01*
X925450Y842936D01*
X926105Y840602D01*
X926978Y838852D01*
X928288Y837394D01*
X930035Y836811D01*
X931781Y837394D01*
X933092Y838852D01*
X933965Y840602D01*
X934620Y842936D01*
X934838Y845561D01*
X934620Y848186D01*
X933965Y850520D01*
X933092Y852269D01*
X931781Y853728D01*
X930035Y854311D01*
G01X947535Y836228D02*
X947098Y836519D01*
Y837103D01*
X947535Y837394D01*
X947972Y837103D01*
Y836519D01*
X947535Y836228D01*
G01X965035Y854311D02*
X963288Y853728D01*
X961978Y852269D01*
X961105Y850520D01*
X960450Y848186D01*
X960232Y845561D01*
X960450Y842936D01*
X961105Y840602D01*
X961978Y838852D01*
X963288Y837394D01*
X965035Y836811D01*
X966781Y837394D01*
X968092Y838852D01*
X968965Y840602D01*
X969620Y842936D01*
X969838Y845561D01*
X969620Y848186D01*
X968965Y850520D01*
X968092Y852269D01*
X966781Y853728D01*
X965035Y854311D01*
G01X1045985Y888961D02*
X1049041Y871461D01*
X1052535Y888961D01*
X1056028Y871461D01*
X1059085Y888961D01*
G01X1067415D02*
X1072655D01*
G01X1070035D02*
Y871461D01*
G01X1067415D02*
X1072655D01*
G01X1082732D02*
Y888961D01*
X1087098D01*
X1088845Y888086D01*
X1090155Y886919D01*
X1091247Y885170D01*
X1092120Y883127D01*
X1092338Y880211D01*
X1092120Y877294D01*
X1091247Y875252D01*
X1090155Y873502D01*
X1088845Y872336D01*
X1087098Y871461D01*
X1082732D01*
G01X1105035Y888961D02*
Y871461D01*
G01X1100013Y888961D02*
X1110057D01*
G01X1117950Y871461D02*
Y888961D01*
G01X1127120D02*
Y871461D01*
G01Y880211D02*
X1117950D01*
G01X1138943Y865628D02*
X1136760Y868544D01*
X1135668Y871461D01*
Y883127D01*
X1136760Y886044D01*
X1138943Y888961D01*
G01X1150985Y871461D02*
Y883127D01*
G01Y879919D02*
X1151640Y881378D01*
X1152732Y882544D01*
X1154260Y883127D01*
X1155788Y882544D01*
X1156880Y881378D01*
X1157535Y879919D01*
Y871461D01*
G01Y879919D02*
X1158190Y881378D01*
X1159281Y882544D01*
X1160810Y883127D01*
X1162338Y882544D01*
X1163430Y881378D01*
X1164085Y879628D01*
Y871461D01*
G01X1175035Y883127D02*
Y871461D01*
G01Y887794D02*
X1174598Y888086D01*
Y888669D01*
X1175035Y888961D01*
X1175472Y888669D01*
Y888086D01*
X1175035Y887794D01*
G01X1192535Y871461D02*
Y888961D01*
G01X1206760Y873502D02*
X1207852Y872336D01*
X1209380Y871461D01*
X1210690D01*
X1212000Y872044D01*
X1212873Y872919D01*
X1213310Y874085D01*
X1213092Y875836D01*
X1212218Y876711D01*
X1208288Y878461D01*
X1207415Y880503D01*
X1207852Y881961D01*
X1208725Y882836D01*
X1210035Y883127D01*
X1211345Y882836D01*
X1212655Y881961D01*
G01X1228627Y865628D02*
X1230810Y868544D01*
X1231902Y871461D01*
Y883127D01*
X1230810Y886044D01*
X1228627Y888961D01*
G01X1109637Y851394D02*
X1110947Y853144D01*
X1112475Y854019D01*
X1114222Y854311D01*
X1116405Y853728D01*
X1117933Y852269D01*
X1118370Y850520D01*
X1118152Y848769D01*
X1117278Y847311D01*
X1112912Y844394D01*
X1110947Y842353D01*
X1109637Y839435D01*
X1109200Y836811D01*
X1118370D01*
G01X1131285Y854311D02*
X1129538Y853728D01*
X1128228Y852269D01*
X1127355Y850520D01*
X1126700Y848186D01*
X1126482Y845561D01*
X1126700Y842936D01*
X1127355Y840602D01*
X1128228Y838852D01*
X1129538Y837394D01*
X1131285Y836811D01*
X1133031Y837394D01*
X1134342Y838852D01*
X1135215Y840602D01*
X1135870Y842936D01*
X1136088Y845561D01*
X1135870Y848186D01*
X1135215Y850520D01*
X1134342Y852269D01*
X1133031Y853728D01*
X1131285Y854311D01*
G01X1148785Y836228D02*
X1148348Y836519D01*
Y837103D01*
X1148785Y837394D01*
X1149222Y837103D01*
Y836519D01*
X1148785Y836228D01*
G01X1166285Y854311D02*
X1164538Y853728D01*
X1163228Y852269D01*
X1162355Y850520D01*
X1161700Y848186D01*
X1161482Y845561D01*
X1161700Y842936D01*
X1162355Y840602D01*
X1163228Y838852D01*
X1164538Y837394D01*
X1166285Y836811D01*
X1168031Y837394D01*
X1169342Y838852D01*
X1170215Y840602D01*
X1170870Y842936D01*
X1171088Y845561D01*
X1170870Y848186D01*
X1170215Y850520D01*
X1169342Y852269D01*
X1168031Y853728D01*
X1166285Y854311D01*
G01X1280035Y888961D02*
Y871461D01*
G01X1275013Y888961D02*
X1285057D01*
G01X1297535Y871461D02*
Y879336D01*
X1293168Y888961D01*
G01X1301902D02*
X1297535Y879336D01*
G01X1310668Y871461D02*
Y888961D01*
X1315908D01*
X1317655Y888086D01*
X1318965Y886044D01*
X1319402Y883711D01*
X1318965Y881378D01*
X1317873Y879628D01*
X1315908Y878752D01*
X1310668D01*
G01X1336902Y871461D02*
X1328168D01*
Y888961D01*
X1336902D01*
G01X1333408Y880503D02*
X1328168D01*
G01X1292950Y839144D02*
X1294697Y837686D01*
X1296662Y836811D01*
X1298408D01*
X1300155Y837686D01*
X1301465Y839144D01*
X1302120Y841186D01*
X1301683Y843227D01*
X1300592Y844978D01*
X1298627Y846144D01*
X1296007Y846728D01*
X1294478Y847894D01*
X1293823Y849936D01*
X1294260Y851978D01*
X1295352Y853436D01*
X1296880Y854311D01*
X1298408D01*
X1299937Y853728D01*
X1301247Y852269D01*
G01X1319402Y836811D02*
X1310668D01*
Y854311D01*
X1319402D01*
G01X1315908Y845853D02*
X1310668D01*
G01X1380668Y871461D02*
Y888961D01*
X1386127D01*
X1387873Y888086D01*
X1388965Y886919D01*
X1389402Y884586D01*
X1388965Y882252D01*
X1387655Y880794D01*
X1386127Y879919D01*
X1380668D01*
G01X1386127D02*
X1389402Y871461D01*
G01X1399260Y879336D02*
X1406247D01*
X1405592Y881378D01*
X1404500Y882544D01*
X1402972Y883127D01*
X1401443Y882836D01*
X1400133Y881961D01*
X1399260Y879919D01*
X1398823Y878169D01*
Y876419D01*
X1399260Y874669D01*
X1400352Y872919D01*
X1401662Y871753D01*
X1403190Y871461D01*
X1404718Y872044D01*
X1406247Y873794D01*
G01X1418725Y871461D02*
Y886336D01*
X1419162Y887794D01*
X1420035Y888669D01*
X1421345Y888961D01*
X1422655Y888378D01*
X1423310Y886919D01*
G01X1420690Y881961D02*
X1416323D01*
G01X1437535Y870878D02*
X1437098Y871169D01*
Y871753D01*
X1437535Y872044D01*
X1437972Y871753D01*
Y871169D01*
X1437535Y870878D01*
G01X1468168Y871461D02*
Y888961D01*
X1473408D01*
X1475155Y888086D01*
X1476465Y886044D01*
X1476902Y883711D01*
X1476465Y881378D01*
X1475373Y879628D01*
X1473408Y878752D01*
X1468168D01*
G01X1490035Y871461D02*
Y888961D01*
G01X1511465Y871461D02*
Y883127D01*
G01Y881086D02*
X1510592Y882252D01*
X1509281Y882836D01*
X1507753Y883127D01*
X1506225Y882544D01*
X1504915Y881378D01*
X1504041Y879628D01*
X1503605Y877294D01*
X1504041Y874961D01*
X1504915Y873211D01*
X1506225Y872044D01*
X1507753Y871461D01*
X1509281Y871753D01*
X1510592Y872627D01*
X1511465Y873794D01*
G01X1521323Y871461D02*
Y883127D01*
G01Y880211D02*
X1522197Y881669D01*
X1523507Y882836D01*
X1525253Y883127D01*
X1526781Y882836D01*
X1528092Y881669D01*
X1528747Y879628D01*
Y871461D01*
G01X1539260Y879336D02*
X1546247D01*
X1545592Y881378D01*
X1544500Y882544D01*
X1542972Y883127D01*
X1541443Y882836D01*
X1540133Y881961D01*
X1539260Y879919D01*
X1538823Y878169D01*
Y876419D01*
X1539260Y874669D01*
X1540352Y872919D01*
X1541662Y871753D01*
X1543190Y871461D01*
X1544718Y872044D01*
X1546247Y873794D01*
G01X1450668Y854311D02*
Y836811D01*
X1459402D01*
G01X1468387Y851394D02*
X1469697Y853144D01*
X1471225Y854019D01*
X1472972Y854311D01*
X1475155Y853728D01*
X1476683Y852269D01*
X1477120Y850520D01*
X1476902Y848769D01*
X1476028Y847311D01*
X1471662Y844394D01*
X1469697Y842353D01*
X1468387Y839435D01*
X1467950Y836811D01*
X1477120D01*
G01X1660335Y848477D02*
Y836811D01*
G01Y853144D02*
X1659898Y853436D01*
Y854019D01*
X1660335Y854311D01*
X1660772Y854019D01*
Y853436D01*
X1660335Y853144D01*
G01X1674560Y838852D02*
X1675652Y837686D01*
X1677180Y836811D01*
X1678490D01*
X1679800Y837394D01*
X1680673Y838269D01*
X1681110Y839435D01*
X1680892Y841186D01*
X1680018Y842061D01*
X1676088Y843811D01*
X1675215Y845853D01*
X1675652Y847311D01*
X1676525Y848186D01*
X1677835Y848477D01*
X1679145Y848186D01*
X1680455Y847311D01*
G01X1707813Y836811D02*
Y854311D01*
X1717857Y836811D01*
Y854311D01*
G01X1730335Y836811D02*
X1728588Y837103D01*
X1727060Y838269D01*
X1725750Y840019D01*
X1724876Y842061D01*
X1724440Y844394D01*
Y846728D01*
X1724876Y849061D01*
X1725750Y851103D01*
X1727060Y852852D01*
X1728588Y854019D01*
X1730335Y854311D01*
X1732081Y854019D01*
X1733610Y852852D01*
X1734920Y851103D01*
X1735794Y849061D01*
X1736230Y846728D01*
Y844394D01*
X1735794Y842061D01*
X1734920Y840019D01*
X1733610Y838269D01*
X1732081Y837103D01*
X1730335Y836811D01*
G01X1747835Y854311D02*
Y836811D01*
G01X1742813Y854311D02*
X1752857D01*
G01X1779123Y848477D02*
Y840311D01*
X1779997Y838269D01*
X1781307Y837103D01*
X1782835Y836811D01*
X1784363Y837103D01*
X1785673Y838269D01*
X1786547Y840311D01*
G01Y836811D02*
Y848477D01*
G01X1797060Y838852D02*
X1798152Y837686D01*
X1799680Y836811D01*
X1800990D01*
X1802300Y837394D01*
X1803173Y838269D01*
X1803610Y839435D01*
X1803392Y841186D01*
X1802518Y842061D01*
X1798588Y843811D01*
X1797715Y845853D01*
X1798152Y847311D01*
X1799025Y848186D01*
X1800335Y848477D01*
X1801645Y848186D01*
X1802955Y847311D01*
G01X1814560Y844686D02*
X1821547D01*
X1820892Y846728D01*
X1819800Y847894D01*
X1818272Y848477D01*
X1816743Y848186D01*
X1815433Y847311D01*
X1814560Y845269D01*
X1814123Y843519D01*
Y841769D01*
X1814560Y840019D01*
X1815652Y838269D01*
X1816962Y837103D01*
X1818490Y836811D01*
X1820018Y837394D01*
X1821547Y839144D01*
G01X1839265Y854311D02*
Y836811D01*
G01Y839435D02*
X1838392Y837977D01*
X1837081Y837103D01*
X1835553Y836811D01*
X1833807Y837394D01*
X1832497Y838852D01*
X1831623Y840602D01*
X1831405Y842644D01*
X1831623Y844686D01*
X1832497Y846436D01*
X1833807Y847894D01*
X1835553Y848477D01*
X1837081Y848186D01*
X1838173Y847602D01*
X1839265Y846436D01*
G01X1870335Y848477D02*
Y836811D01*
G01Y853144D02*
X1869898Y853436D01*
Y854019D01*
X1870335Y854311D01*
X1870772Y854019D01*
Y853436D01*
X1870335Y853144D01*
G01X1884123Y836811D02*
Y848477D01*
G01Y845561D02*
X1884997Y847019D01*
X1886307Y848186D01*
X1888053Y848477D01*
X1889581Y848186D01*
X1890892Y847019D01*
X1891547Y844978D01*
Y836811D01*
G01X1922835Y854311D02*
Y836811D01*
G01X1919778Y848477D02*
X1925892D01*
G01X1936623Y836811D02*
Y854311D01*
G01Y845853D02*
X1937715Y847311D01*
X1938807Y848186D01*
X1940553Y848477D01*
X1941863Y848186D01*
X1943392Y847019D01*
X1944047Y845269D01*
Y836811D01*
G01X1957835Y848477D02*
Y836811D01*
G01Y853144D02*
X1957398Y853436D01*
Y854019D01*
X1957835Y854311D01*
X1958272Y854019D01*
Y853436D01*
X1957835Y853144D01*
G01X1972060Y838852D02*
X1973152Y837686D01*
X1974680Y836811D01*
X1975990D01*
X1977300Y837394D01*
X1978173Y838269D01*
X1978610Y839435D01*
X1978392Y841186D01*
X1977518Y842061D01*
X1973588Y843811D01*
X1972715Y845853D01*
X1973152Y847311D01*
X1974025Y848186D01*
X1975335Y848477D01*
X1976645Y848186D01*
X1977955Y847311D01*
G01X2010335Y836811D02*
Y854311D01*
G01X2031765Y836811D02*
Y848477D01*
G01Y846436D02*
X2030892Y847602D01*
X2029581Y848186D01*
X2028053Y848477D01*
X2026525Y847894D01*
X2025215Y846728D01*
X2024341Y844978D01*
X2023905Y842644D01*
X2024341Y840311D01*
X2025215Y838561D01*
X2026525Y837394D01*
X2028053Y836811D01*
X2029581Y837103D01*
X2030892Y837977D01*
X2031765Y839144D01*
G01X2040750Y831561D02*
X2042060Y830978D01*
X2043807Y831561D01*
X2044898Y832727D01*
X2045772Y834186D01*
X2047081Y838852D01*
X2049920Y848477D01*
G01X2042933D02*
X2047081Y838852D01*
G01X2059560Y844686D02*
X2066547D01*
X2065892Y846728D01*
X2064800Y847894D01*
X2063272Y848477D01*
X2061743Y848186D01*
X2060433Y847311D01*
X2059560Y845269D01*
X2059123Y843519D01*
Y841769D01*
X2059560Y840019D01*
X2060652Y838269D01*
X2061962Y837103D01*
X2063490Y836811D01*
X2065018Y837394D01*
X2066547Y839144D01*
G01X2077278Y836811D02*
Y848477D01*
G01Y846144D02*
X2078370Y847311D01*
X2079462Y848186D01*
X2080990Y848477D01*
X2082081Y848186D01*
X2083392Y847311D01*
G01X1660335Y813827D02*
Y802161D01*
G01Y818494D02*
X1659898Y818786D01*
Y819369D01*
X1660335Y819661D01*
X1660772Y819369D01*
Y818786D01*
X1660335Y818494D01*
G01X1674123Y802161D02*
Y813827D01*
G01Y810911D02*
X1674997Y812369D01*
X1676307Y813536D01*
X1678053Y813827D01*
X1679581Y813536D01*
X1680892Y812369D01*
X1681547Y810328D01*
Y802161D01*
G01X1692060Y804202D02*
X1693152Y803036D01*
X1694680Y802161D01*
X1695990D01*
X1697300Y802744D01*
X1698173Y803619D01*
X1698610Y804785D01*
X1698392Y806536D01*
X1697518Y807411D01*
X1693588Y809161D01*
X1692715Y811203D01*
X1693152Y812661D01*
X1694025Y813536D01*
X1695335Y813827D01*
X1696645Y813536D01*
X1697955Y812661D01*
G01X1712835Y813827D02*
Y802161D01*
G01Y818494D02*
X1712398Y818786D01*
Y819369D01*
X1712835Y819661D01*
X1713272Y819369D01*
Y818786D01*
X1712835Y818494D01*
G01X1734265Y819661D02*
Y802161D01*
G01Y804785D02*
X1733392Y803327D01*
X1732081Y802453D01*
X1730553Y802161D01*
X1728807Y802744D01*
X1727497Y804202D01*
X1726623Y805952D01*
X1726405Y807994D01*
X1726623Y810036D01*
X1727497Y811786D01*
X1728807Y813244D01*
X1730553Y813827D01*
X1732081Y813536D01*
X1733173Y812952D01*
X1734265Y811786D01*
G01X1744560Y810036D02*
X1751547D01*
X1750892Y812078D01*
X1749800Y813244D01*
X1748272Y813827D01*
X1746743Y813536D01*
X1745433Y812661D01*
X1744560Y810619D01*
X1744123Y808869D01*
Y807119D01*
X1744560Y805369D01*
X1745652Y803619D01*
X1746962Y802453D01*
X1748490Y802161D01*
X1750018Y802744D01*
X1751547Y804494D01*
G01X1778905Y802161D02*
Y819661D01*
G01Y810911D02*
X1779997Y812661D01*
X1781307Y813536D01*
X1782617Y813827D01*
X1784581Y813244D01*
X1785892Y812078D01*
X1786765Y810036D01*
Y807703D01*
X1786328Y805369D01*
X1785455Y803619D01*
X1783927Y802453D01*
X1782617Y802161D01*
X1781307Y802453D01*
X1779997Y803327D01*
X1778905Y804785D01*
G01X1800335Y802161D02*
X1799025Y802453D01*
X1797715Y803619D01*
X1796841Y805661D01*
X1796405Y807994D01*
X1796841Y810328D01*
X1797715Y812369D01*
X1799025Y813536D01*
X1800335Y813827D01*
X1801645Y813536D01*
X1802955Y812369D01*
X1803828Y810328D01*
X1804047Y807994D01*
X1803828Y805661D01*
X1802955Y803619D01*
X1801645Y802453D01*
X1800335Y802161D01*
G01X1821765D02*
Y813827D01*
G01Y811786D02*
X1820892Y812952D01*
X1819581Y813536D01*
X1818053Y813827D01*
X1816525Y813244D01*
X1815215Y812078D01*
X1814341Y810328D01*
X1813905Y807994D01*
X1814341Y805661D01*
X1815215Y803911D01*
X1816525Y802744D01*
X1818053Y802161D01*
X1819581Y802453D01*
X1820892Y803327D01*
X1821765Y804494D01*
G01X1832278Y802161D02*
Y813827D01*
G01Y811494D02*
X1833370Y812661D01*
X1834462Y813536D01*
X1835990Y813827D01*
X1837081Y813536D01*
X1838392Y812661D01*
G01X1856765Y819661D02*
Y802161D01*
G01Y804785D02*
X1855892Y803327D01*
X1854581Y802453D01*
X1853053Y802161D01*
X1851307Y802744D01*
X1849997Y804202D01*
X1849123Y805952D01*
X1848905Y807994D01*
X1849123Y810036D01*
X1849997Y811786D01*
X1851307Y813244D01*
X1853053Y813827D01*
X1854581Y813536D01*
X1855673Y812952D01*
X1856765Y811786D01*
G01X1887835Y802161D02*
X1886525Y802453D01*
X1885215Y803619D01*
X1884341Y805661D01*
X1883905Y807994D01*
X1884341Y810328D01*
X1885215Y812369D01*
X1886525Y813536D01*
X1887835Y813827D01*
X1889145Y813536D01*
X1890455Y812369D01*
X1891328Y810328D01*
X1891547Y807994D01*
X1891328Y805661D01*
X1890455Y803619D01*
X1889145Y802453D01*
X1887835Y802161D01*
G01X1901623Y813827D02*
Y805661D01*
X1902497Y803619D01*
X1903807Y802453D01*
X1905335Y802161D01*
X1906863Y802453D01*
X1908173Y803619D01*
X1909047Y805661D01*
G01Y802161D02*
Y813827D01*
G01X1922835Y819661D02*
Y802161D01*
G01X1919778Y813827D02*
X1925892D01*
G01X1940335Y802161D02*
Y819661D01*
G01X1957835Y813827D02*
Y802161D01*
G01Y818494D02*
X1957398Y818786D01*
Y819369D01*
X1957835Y819661D01*
X1958272Y819369D01*
Y818786D01*
X1957835Y818494D01*
G01X1971623Y802161D02*
Y813827D01*
G01Y810911D02*
X1972497Y812369D01*
X1973807Y813536D01*
X1975553Y813827D01*
X1977081Y813536D01*
X1978392Y812369D01*
X1979047Y810328D01*
Y802161D01*
G01X1989560Y810036D02*
X1996547D01*
X1995892Y812078D01*
X1994800Y813244D01*
X1993272Y813827D01*
X1991743Y813536D01*
X1990433Y812661D01*
X1989560Y810619D01*
X1989123Y808869D01*
Y807119D01*
X1989560Y805369D01*
X1990652Y803619D01*
X1991962Y802453D01*
X1993490Y802161D01*
X1995018Y802744D01*
X1996547Y804494D01*
G01X2010335Y801578D02*
X2009898Y801869D01*
Y802453D01*
X2010335Y802744D01*
X2010772Y802453D01*
Y801869D01*
X2010335Y801578D01*
G01X1585532Y870878D02*
X1595138Y883711D01*
G01X1590335Y886044D02*
Y868544D01*
G01X1595138Y870878D02*
X1585532Y883711D01*
G01X1583785Y877294D02*
X1596885D01*
G01X1622497D02*
X1628173D01*
G01X1655532Y871461D02*
Y888961D01*
X1659898D01*
X1661645Y888086D01*
X1662955Y886919D01*
X1664047Y885170D01*
X1664920Y883127D01*
X1665138Y880211D01*
X1664920Y877294D01*
X1664047Y875252D01*
X1662955Y873502D01*
X1661645Y872336D01*
X1659898Y871461D01*
X1655532D01*
G01X1674560Y879336D02*
X1681547D01*
X1680892Y881378D01*
X1679800Y882544D01*
X1678272Y883127D01*
X1676743Y882836D01*
X1675433Y881961D01*
X1674560Y879919D01*
X1674123Y878169D01*
Y876419D01*
X1674560Y874669D01*
X1675652Y872919D01*
X1676962Y871753D01*
X1678490Y871461D01*
X1680018Y872044D01*
X1681547Y873794D01*
G01X1691623Y871461D02*
Y883127D01*
G01Y880211D02*
X1692497Y881669D01*
X1693807Y882836D01*
X1695553Y883127D01*
X1697081Y882836D01*
X1698392Y881669D01*
X1699047Y879628D01*
Y871461D01*
G01X1712835D02*
X1711525Y871753D01*
X1710215Y872919D01*
X1709341Y874961D01*
X1708905Y877294D01*
X1709341Y879628D01*
X1710215Y881669D01*
X1711525Y882836D01*
X1712835Y883127D01*
X1714145Y882836D01*
X1715455Y881669D01*
X1716328Y879628D01*
X1716547Y877294D01*
X1716328Y874961D01*
X1715455Y872919D01*
X1714145Y871753D01*
X1712835Y871461D01*
G01X1730335Y888961D02*
Y871461D01*
G01X1727278Y883127D02*
X1733392D01*
G01X1744560Y879336D02*
X1751547D01*
X1750892Y881378D01*
X1749800Y882544D01*
X1748272Y883127D01*
X1746743Y882836D01*
X1745433Y881961D01*
X1744560Y879919D01*
X1744123Y878169D01*
Y876419D01*
X1744560Y874669D01*
X1745652Y872919D01*
X1746962Y871753D01*
X1748490Y871461D01*
X1750018Y872044D01*
X1751547Y873794D01*
G01X1762060Y873502D02*
X1763152Y872336D01*
X1764680Y871461D01*
X1765990D01*
X1767300Y872044D01*
X1768173Y872919D01*
X1768610Y874085D01*
X1768392Y875836D01*
X1767518Y876711D01*
X1763588Y878461D01*
X1762715Y880503D01*
X1763152Y881961D01*
X1764025Y882836D01*
X1765335Y883127D01*
X1766645Y882836D01*
X1767955Y881961D01*
G01X1800335Y888961D02*
Y871461D01*
G01X1797278Y883127D02*
X1803392D01*
G01X1814123Y871461D02*
Y888961D01*
G01Y880503D02*
X1815215Y881961D01*
X1816307Y882836D01*
X1818053Y883127D01*
X1819363Y882836D01*
X1820892Y881669D01*
X1821547Y879919D01*
Y871461D01*
G01X1839265D02*
Y883127D01*
G01Y881086D02*
X1838392Y882252D01*
X1837081Y882836D01*
X1835553Y883127D01*
X1834025Y882544D01*
X1832715Y881378D01*
X1831841Y879628D01*
X1831405Y877294D01*
X1831841Y874961D01*
X1832715Y873211D01*
X1834025Y872044D01*
X1835553Y871461D01*
X1837081Y871753D01*
X1838392Y872627D01*
X1839265Y873794D01*
G01X1852835Y888961D02*
Y871461D01*
G01X1849778Y883127D02*
X1855892D01*
G01X1881285Y888961D02*
X1884341Y871461D01*
X1887835Y888961D01*
X1891328Y871461D01*
X1894385Y888961D01*
G01X1902715D02*
X1907955D01*
G01X1905335D02*
Y871461D01*
G01X1902715D02*
X1907955D01*
G01X1918032D02*
Y888961D01*
X1922398D01*
X1924145Y888086D01*
X1925455Y886919D01*
X1926547Y885170D01*
X1927420Y883127D01*
X1927638Y880211D01*
X1927420Y877294D01*
X1926547Y875252D01*
X1925455Y873502D01*
X1924145Y872336D01*
X1922398Y871461D01*
X1918032D01*
G01X1940335Y888961D02*
Y871461D01*
G01X1935313Y888961D02*
X1945357D01*
G01X1953250Y871461D02*
Y888961D01*
G01X1962420D02*
Y871461D01*
G01Y880211D02*
X1953250D01*
G01X21279Y19685D02*
G03X11201I-5039J0D01*
G01D02*
G03X21279I5039J0D01*
G01X3937Y-3937D02*
X724409D01*
G01X0Y0D02*
G03X3937Y-3937I3937J0D01*
G01X0Y35433D02*
Y0D01*
G01Y51181D02*
G03X3937Y47244I3937J0D01*
G01X0Y51181D02*
Y118898D01*
G01X4724Y47244D02*
X3937D01*
G01X29921Y63780D02*
Y47244D01*
G01X41732Y75591D02*
G03X29921Y63780I0J-11811D01*
G01X4724Y39370D02*
G03Y47244I0J3937D01*
G01X29921D02*
G03Y39370I0J-3937D01*
G01X3937D02*
G03X0Y35433I0J-3937D01*
G01X33858Y39370D02*
X3937D01*
G01X33858D02*
G03X37795Y43307I0J3937D01*
G01Y63780D02*
Y43307D01*
G01X41732Y67717D02*
G03X37795Y63780I0J-3937D01*
G01X65354Y67717D02*
X41732D01*
G01X3937Y122835D02*
G03X0Y118898I0J-3937D01*
G01X60828Y75591D02*
X41732D01*
G01X20531Y99213D02*
G03I-4291J0D01*
G01X29921Y122835D02*
X60828D01*
G01X21279Y154331D02*
G03X11201I-5039J0D01*
G01D02*
G03X21279I5039J0D01*
G01X3937Y130709D02*
X724409D01*
G01X0Y134646D02*
G03X3937Y130709I3937J0D01*
G01X0Y170079D02*
Y134646D01*
G01X4724Y122835D02*
G03Y130709I0J3937D01*
G01X29921D02*
G03Y122835I0J-3937D01*
G01X4724D02*
X3937D01*
G01X0Y185827D02*
G03X3937Y181890I3937J0D01*
G01X0Y185827D02*
Y253544D01*
G01X4724Y181890D02*
X3937D01*
G01X29921Y198426D02*
Y181890D01*
G01X41732Y210237D02*
G03X29921Y198426I0J-11811D01*
G01X60828Y210237D02*
X41732D01*
G01X4724Y174016D02*
G03Y181890I0J3937D01*
G01X29921D02*
G03Y174016I0J-3937D01*
G01X3937D02*
G03X0Y170079I0J-3937D01*
G01X33858Y174016D02*
X3937D01*
G01X33858D02*
G03X37795Y177953I0J3937D01*
G01Y198426D02*
Y177953D01*
G01X41732Y202363D02*
G03X37795Y198426I0J-3937D01*
G01X65354Y202363D02*
X41732D01*
G01X29921Y257481D02*
X60828D01*
G01X3937D02*
G03X0Y253544I0J-3937D01*
G01X4724Y257481D02*
G03Y265355I0J3937D01*
G01X29921D02*
G03Y257481I0J-3937D01*
G01X4724D02*
X3937D01*
G01X20531Y233859D02*
G03I-4291J0D01*
G01X4724Y308662D02*
G03Y316536I0J3937D01*
G01X29921D02*
G03Y308662I0J-3937D01*
G01X21279Y288977D02*
G03X11201I-5039J0D01*
G01D02*
G03X21279I5039J0D01*
G01X3937Y265355D02*
X724409D01*
G01X0Y269292D02*
G03X3937Y265355I3937J0D01*
G01X0Y304725D02*
Y269292D01*
G01X3937Y308662D02*
G03X0Y304725I0J-3937D01*
G01X33858Y308662D02*
X3937D01*
G01X33858D02*
G03X37795Y312599I0J3937D01*
G01X0Y320473D02*
G03X3937Y316536I3937J0D01*
G01X0Y320473D02*
Y388190D01*
G01X4724Y316536D02*
X3937D01*
G01X29921Y333072D02*
Y316536D01*
G01X41732Y344883D02*
G03X29921Y333072I0J-11811D01*
G01X60828Y344883D02*
X41732D01*
G01X37795Y333072D02*
Y312599D01*
G01X41732Y337009D02*
G03X37795Y333072I0J-3937D01*
G01X65354Y337009D02*
X41732D01*
G01X29921Y392127D02*
X60828D01*
G01X3937D02*
G03X0Y388190I0J-3937D01*
G01X4724Y392127D02*
G03Y400001I0J3937D01*
G01X29921D02*
G03Y392127I0J-3937D01*
G01X4724D02*
X3937D01*
G01X20531Y368505D02*
G03I-4291J0D01*
G01X3937Y400001D02*
X724409D01*
G01X0Y403938D02*
G03X3937Y400001I3937J0D01*
G01X0Y439371D02*
Y403938D01*
G01Y455119D02*
G03X3937Y451182I3937J0D01*
G01X4724D02*
X3937D01*
G01X29921Y467718D02*
Y451182D01*
G01X4724Y443308D02*
G03Y451182I0J3937D01*
G01X29921D02*
G03Y443308I0J-3937D01*
G01X21279Y423623D02*
G03X11201I-5039J0D01*
G01D02*
G03X21279I5039J0D01*
G01X3937Y443308D02*
G03X0Y439371I0J-3937D01*
G01X33858Y443308D02*
X3937D01*
G01X33858D02*
G03X37795Y447245I0J3937D01*
G01Y467718D02*
Y447245D01*
G01X0Y455119D02*
Y522836D01*
G01X41732Y479529D02*
G03X29921Y467718I0J-11811D01*
G01X60828Y479529D02*
X41732D01*
G01X20531Y503151D02*
G03I-4291J0D01*
G01X41732Y471655D02*
G03X37795Y467718I0J-3937D01*
G01X65354Y471655D02*
X41732D01*
G01X29921Y526773D02*
X60828D01*
G01X3937D02*
G03X0Y522836I0J-3937D01*
G01X4724Y526773D02*
G03Y534647I0J3937D01*
G01X29921D02*
G03Y526773I0J-3937D01*
G01X4724D02*
X3937D01*
G01Y534647D02*
X724409D01*
G01X0Y538584D02*
G03X3937Y534647I3937J0D01*
G01X0Y574017D02*
Y538584D01*
G01Y589765D02*
G03X3937Y585828I3937J0D01*
G01X0Y589765D02*
Y657482D01*
G01X4724Y585828D02*
X3937D01*
G01X29921Y602364D02*
Y585828D01*
G01X4724Y577954D02*
G03Y585828I0J3937D01*
G01X29921D02*
G03Y577954I0J-3937D01*
G01X21279Y558269D02*
G03X11201I-5039J0D01*
G01D02*
G03X21279I5039J0D01*
G01X3937Y577954D02*
G03X0Y574017I0J-3937D01*
G01X33858Y577954D02*
X3937D01*
G01X33858D02*
G03X37795Y581891I0J3937D01*
G01Y602364D02*
Y581891D01*
G01X41732Y614175D02*
G03X29921Y602364I0J-11811D01*
G01X60828Y614175D02*
X41732D01*
G01X20531Y637797D02*
G03I-4291J0D01*
G01X41732Y606301D02*
G03X37795Y602364I0J-3937D01*
G01X65354Y606301D02*
X41732D01*
G01X29921Y661419D02*
X60828D01*
G01X3937D02*
G03X0Y657482I0J-3937D01*
G01X4724Y661419D02*
G03Y669293I0J3937D01*
G01X29921D02*
G03Y661419I0J-3937D01*
G01X4724D02*
X3937D01*
G01X11201Y692915D02*
G03X21279I5039J0D01*
G01X3937Y669293D02*
X724409D01*
G01X0Y673230D02*
G03X3937Y669293I3937J0D01*
G01X0Y708663D02*
Y673230D01*
G01Y724411D02*
G03X3937Y720474I3937J0D01*
G01X0Y724411D02*
Y792128D01*
G01X4724Y720474D02*
X3937D01*
G01X29921Y737010D02*
Y720474D01*
G01X41732Y748821D02*
G03X29921Y737010I0J-11811D01*
G01X4724Y712600D02*
G03Y720474I0J3937D01*
G01X29921D02*
G03Y712600I0J-3937D01*
G01X21279Y692915D02*
G03X11201I-5039J0D01*
G01X3937Y712600D02*
G03X0Y708663I0J-3937D01*
G01X33858Y712600D02*
X3937D01*
G01X33858D02*
G03X37795Y716537I0J3937D01*
G01Y737010D02*
Y716537D01*
G01X41732Y740947D02*
G03X37795Y737010I0J-3937D01*
G01X60828Y748821D02*
X41732D01*
G01X20531Y772443D02*
G03I-4291J0D01*
G01X65354Y740947D02*
X41732D01*
G01X29921Y796065D02*
X60828D01*
G01X3937D02*
G03X0Y792128I0J-3937D01*
G01X4724Y796065D02*
G03Y803939I0J3937D01*
G01X29921D02*
G03Y796065I0J-3937D01*
G01X4724D02*
X3937D01*
G01X21279Y827561D02*
G03X11201I-5039J0D01*
G01D02*
G03X21279I5039J0D01*
G01X3937Y803939D02*
X724409D01*
G01X0Y807876D02*
G03X3937Y803939I3937J0D01*
G01X0Y843309D02*
Y807876D01*
G01Y859057D02*
G03X3937Y855120I3937J0D01*
G01X0Y859057D02*
Y922837D01*
G01X4724Y855120D02*
X3937D01*
G01X29921Y871656D02*
Y855120D01*
G01X41732Y883467D02*
G03X29921Y871656I0J-11811D01*
G01X4724Y847246D02*
G03Y855120I0J3937D01*
G01X29921D02*
G03Y847246I0J-3937D01*
G01X3937D02*
G03X0Y843309I0J-3937D01*
G01X33858Y847246D02*
X3937D01*
G01X33858D02*
G03X37795Y851183I0J3937D01*
G01Y871656D02*
Y851183D01*
G01X41732Y875593D02*
G03X37795Y871656I0J-3937D01*
G01X65354Y875593D02*
X41732D01*
G01X7874Y930711D02*
G03X0Y922837I0J-7874D01*
G01X60828Y883467D02*
X41732D01*
G01X20531Y907089D02*
G03I-4291J0D01*
G01X60828Y930711D02*
X7874D01*
G01X53445Y19685D02*
G03X42028I-5709J0D01*
G01D02*
G03X53445I5709J0D01*
G01X69291Y63780D02*
G03X65354Y67717I-3937J0D01*
G01X69291Y43307D02*
Y63780D01*
G01Y43307D02*
G03X73228Y39370I3937J0D01*
G01X156102D02*
X73228D01*
G01X64765Y118898D02*
G03X60828Y122835I-3937J0D01*
G01Y75591D02*
G03X64765Y79528I0J3937D01*
G01Y113780D02*
Y118898D01*
G01X72639Y88583D02*
G03X64765I-3937J0D01*
G01Y113780D02*
G03X72639I3937J0D01*
G01X64765Y88583D02*
Y79528D01*
G01X83879Y99213D02*
G03X93879I5000J0D01*
G01D02*
G03X83879I-5000J0D01*
G01X76576Y122835D02*
G03X72639Y118898I0J-3937D01*
G01X76576Y79528D02*
X106694D01*
G01X72639Y83465D02*
G03X76576Y79528I3937J0D01*
G01X72639Y118898D02*
Y83465D01*
G01X53445Y154331D02*
G03X42028I-5709J0D01*
G01D02*
G03X53445I5709J0D01*
G01X797048Y122835D02*
X76576D01*
G01X60828Y210237D02*
G03X64765Y214174I0J3937D01*
G01Y223229D02*
Y214174D01*
G01X76576D02*
X106694D01*
G01X72639Y218111D02*
G03X76576Y214174I3937J0D01*
G01X69291Y198426D02*
G03X65354Y202363I-3937J0D01*
G01X69291Y177953D02*
Y198426D01*
G01Y177953D02*
G03X73228Y174016I3937J0D01*
G01X156102D02*
X73228D01*
G01X64765Y253544D02*
G03X60828Y257481I-3937J0D01*
G01X64765Y248426D02*
Y253544D01*
G01X72639Y223229D02*
G03X64765I-3937J0D01*
G01Y248426D02*
G03X72639I3937J0D01*
G01X83879Y233859D02*
G03X93879I5000J0D01*
G01D02*
G03X83879I-5000J0D01*
G01X76576Y257481D02*
G03X72639Y253544I0J-3937D01*
G01X797048Y257481D02*
X76576D01*
G01X72639Y253544D02*
Y218111D01*
G01X53445Y288977D02*
G03X42028I-5709J0D01*
G01D02*
G03X53445I5709J0D01*
G01X69291Y312599D02*
G03X73228Y308662I3937J0D01*
G01X156102D02*
X73228D01*
G01X60828Y344883D02*
G03X64765Y348820I0J3937D01*
G01X72639Y357875D02*
G03X64765I-3937J0D01*
G01D02*
Y348820D01*
G01X76576D02*
X106694D01*
G01X72639Y352757D02*
G03X76576Y348820I3937J0D01*
G01X72639Y388190D02*
Y352757D01*
G01X69291Y333072D02*
G03X65354Y337009I-3937J0D01*
G01X69291Y312599D02*
Y333072D01*
G01X64765Y388190D02*
G03X60828Y392127I-3937J0D01*
G01X64765Y383072D02*
Y388190D01*
G01Y383072D02*
G03X72639I3937J0D01*
G01X83879Y368505D02*
G03X93879I5000J0D01*
G01D02*
G03X83879I-5000J0D01*
G01X76576Y392127D02*
G03X72639Y388190I0J-3937D01*
G01X797048Y392127D02*
X76576D01*
G01X53445Y423623D02*
G03X42028I-5709J0D01*
G01D02*
G03X53445I5709J0D01*
G01X69291Y447245D02*
Y467718D01*
G01Y447245D02*
G03X73228Y443308I3937J0D01*
G01X156102D02*
X73228D01*
G01X60828Y479529D02*
G03X64765Y483466I0J3937D01*
G01X72639Y492521D02*
G03X64765I-3937J0D01*
G01D02*
Y483466D01*
G01X83879Y503151D02*
G03X93879I5000J0D01*
G01X76576Y483466D02*
X106694D01*
G01X72639Y487403D02*
G03X76576Y483466I3937J0D01*
G01X72639Y522836D02*
Y487403D01*
G01X69291Y467718D02*
G03X65354Y471655I-3937J0D01*
G01X64765Y522836D02*
G03X60828Y526773I-3937J0D01*
G01X64765Y517718D02*
Y522836D01*
G01Y517718D02*
G03X72639I3937J0D01*
G01X93879Y503151D02*
G03X83879I-5000J0D01*
G01X76576Y526773D02*
G03X72639Y522836I0J-3937D01*
G01X797048Y526773D02*
X76576D01*
G01X53445Y558269D02*
G03X42028I-5709J0D01*
G01D02*
G03X53445I5709J0D01*
G01X69291Y581891D02*
Y602364D01*
G01Y581891D02*
G03X73228Y577954I3937J0D01*
G01X156102D02*
X73228D01*
G01X60828Y614175D02*
G03X64765Y618112I0J3937D01*
G01X72639Y627167D02*
G03X64765I-3937J0D01*
G01D02*
Y618112D01*
G01X83879Y637797D02*
G03X93879I5000J0D01*
G01D02*
G03X83879I-5000J0D01*
G01X76576Y618112D02*
X106694D01*
G01X72639Y622049D02*
G03X76576Y618112I3937J0D01*
G01X72639Y657482D02*
Y622049D01*
G01X69291Y602364D02*
G03X65354Y606301I-3937J0D01*
G01X64765Y657482D02*
G03X60828Y661419I-3937J0D01*
G01X64765Y652364D02*
Y657482D01*
G01Y652364D02*
G03X72639I3937J0D01*
G01X42028Y692915D02*
G03X53445I5709J0D01*
G01X76576Y661419D02*
G03X72639Y657482I0J-3937D01*
G01X797048Y661419D02*
X76576D01*
G01X53445Y692915D02*
G03X42028I-5709J0D01*
G01X69291Y737010D02*
G03X65354Y740947I-3937J0D01*
G01X69291Y716537D02*
Y737010D01*
G01Y716538D02*
G03X73228Y712601I3937J0D01*
G01X156102Y712600D02*
X73228D01*
G01X60828Y748821D02*
G03X64765Y752758I0J3937D01*
G01Y787010D02*
Y792128D01*
G01X72639Y761813D02*
G03X64765I-3937J0D01*
G01Y787010D02*
G03X72639I3937J0D01*
G01X64765Y761813D02*
Y752758D01*
G01X83879Y772443D02*
G03X93879I5000J0D01*
G01D02*
G03X83879I-5000J0D01*
G01X76576Y752758D02*
X106694D01*
G01X72639Y756695D02*
G03X76576Y752758I3937J0D01*
G01X72639Y792128D02*
Y756695D01*
G01X64765Y792128D02*
G03X60828Y796065I-3937J0D01*
G01X53445Y827561D02*
G03X42028I-5709J0D01*
G01D02*
G03X53445I5709J0D01*
G01X76576Y796065D02*
G03X72639Y792128I0J-3937D01*
G01X797048Y796065D02*
X76576D01*
G01X69291Y871656D02*
G03X65354Y875593I-3937J0D01*
G01X69291Y851183D02*
Y871656D01*
G01Y851184D02*
G03X73228Y847247I3937J0D01*
G01X156102Y847246D02*
X73228D01*
G01X60828Y883467D02*
G03X64765Y887404I0J3937D01*
G01Y926774D02*
G03X60828Y930711I-3937J0D01*
G01X64765Y921656D02*
Y926774D01*
G01X72639Y896459D02*
G03X64765I-3937J0D01*
G01Y921656D02*
G03X72639I3937J0D01*
G01X64765Y896459D02*
Y887404D01*
G01X83879Y907089D02*
G03X93879I5000J0D01*
G01D02*
G03X83879I-5000J0D01*
G01X76576Y930711D02*
G03X72639Y926774I0J-3937D01*
G01X76576Y887404D02*
X106694D01*
G01X72639Y891341D02*
G03X76576Y887404I3937J0D01*
G01X72639Y926774D02*
Y891341D01*
G01X797048Y930711D02*
X76576D01*
G01X114568Y51181D02*
X138190D01*
G01X110631Y55118D02*
G03X114568Y51181I3937J0D01*
G01X110631Y75591D02*
Y55118D01*
G01X114666Y99213D02*
G03X126083I5708J0D01*
G01D02*
G03X114666I-5709J0D01*
G01X110631Y75591D02*
G03X106694Y79528I-3937J0D01*
G01X114568Y185827D02*
X138190D01*
G01X110631Y189764D02*
G03X114568Y185827I3937J0D01*
G01X110631Y210237D02*
Y189764D01*
G01Y210237D02*
G03X106694Y214174I-3937J0D01*
G01X114666Y233859D02*
G03X126083I5708J0D01*
G01D02*
G03X114666I-5709J0D01*
G01X114568Y320473D02*
X138190D01*
G01X110631Y324410D02*
G03X114568Y320473I3937J0D01*
G01X110631Y344883D02*
Y324410D01*
G01Y344883D02*
G03X106694Y348820I-3937J0D01*
G01X114666Y368505D02*
G03X126083I5708J0D01*
G01D02*
G03X114666I-5709J0D01*
G01Y503151D02*
G03X126083I5708J0D01*
G01X114568Y455119D02*
X138190D01*
G01X110631Y459056D02*
G03X114568Y455119I3937J0D01*
G01X110631Y479529D02*
Y459056D01*
G01Y479529D02*
G03X106694Y483466I-3937J0D01*
G01X126083Y503151D02*
G03X114666I-5709J0D01*
G01X114568Y589765D02*
X138190D01*
G01X110631Y593702D02*
G03X114568Y589765I3937J0D01*
G01X110631Y614175D02*
Y593702D01*
G01X114666Y637797D02*
G03X126083I5708J0D01*
G01D02*
G03X114666I-5709J0D01*
G01X110631Y614175D02*
G03X106694Y618112I-3937J0D01*
G01X114568Y724411D02*
X138190D01*
G01X110631Y728348D02*
G03X114568Y724411I3937J0D01*
G01X110631Y748821D02*
Y728348D01*
G01X114666Y772443D02*
G03X126083I5708J0D01*
G01D02*
G03X114666I-5709J0D01*
G01X110631Y748821D02*
G03X106694Y752758I-3937J0D01*
G01X114568Y859057D02*
X138190D01*
G01X110631Y862994D02*
G03X114568Y859057I3937J0D01*
G01X110631Y883467D02*
Y862994D01*
G01X114666Y907089D02*
G03X126083I5708J0D01*
G01D02*
G03X114666I-5709J0D01*
G01X110631Y883467D02*
G03X106694Y887404I-3937J0D01*
G01X142127Y55118D02*
Y75591D01*
G01X138190Y51181D02*
G03X142127Y55118I0J3937D01*
G01X180905Y71654D02*
G03Y79528I0J3937D01*
G01X156102Y39370D02*
G03X160039Y43307I0J3937D01*
G01Y67717D02*
Y43307D01*
G01X163976Y71654D02*
G03X160039Y67717I0J-3937D01*
G01X223031Y71654D02*
X163976D01*
G01X146064Y79528D02*
X230906D01*
G01X146064D02*
G03X142127Y75591I0J-3937D01*
G01X146064Y214174D02*
X230906D01*
G01X146064D02*
G03X142127Y210237I0J-3937D01*
G01Y189764D02*
Y210237D01*
G01X138190Y185827D02*
G03X142127Y189764I0J3937D01*
G01X180905Y206300D02*
G03Y214174I0J3937D01*
G01X156102Y174016D02*
G03X160039Y177953I0J3937D01*
G01Y202363D02*
Y177953D01*
G01X163976Y206300D02*
G03X160039Y202363I0J-3937D01*
G01X223031Y206300D02*
X163976D01*
G01X156102Y308662D02*
G03X160039Y312599I0J3937D01*
G01X146064Y348820D02*
X230906D01*
G01X146064D02*
G03X142127Y344883I0J-3937D01*
G01Y324410D02*
Y344883D01*
G01X138190Y320473D02*
G03X142127Y324410I0J3937D01*
G01X180905Y340946D02*
G03Y348820I0J3937D01*
G01X160039Y337009D02*
Y312599D01*
G01X163976Y340946D02*
G03X160039Y337009I0J-3937D01*
G01X223031Y340946D02*
X163976D01*
G01X156102Y443308D02*
G03X160039Y447245I0J3937D01*
G01Y471655D02*
Y447245D01*
G01X146064Y483466D02*
X230906D01*
G01X146064D02*
G03X142127Y479529I0J-3937D01*
G01Y459056D02*
Y479529D01*
G01X138190Y455120D02*
G03X142127Y459057I0J3937D01*
G01X180905Y475592D02*
G03Y483466I0J3937D01*
G01X163976Y475592D02*
G03X160039Y471655I0J-3937D01*
G01X223031Y475592D02*
X163976D01*
G01X142127Y593702D02*
Y614175D01*
G01X138190Y589766D02*
G03X142127Y593703I0J3937D01*
G01X156102Y577954D02*
G03X160039Y581891I0J3937D01*
G01Y606301D02*
Y581891D01*
G01X146064Y618112D02*
X230906D01*
G01X146064D02*
G03X142127Y614175I0J-3937D01*
G01X180905Y610238D02*
G03Y618112I0J3937D01*
G01X163976Y610238D02*
G03X160039Y606301I0J-3937D01*
G01X223031Y610238D02*
X163976D01*
G01X142127Y728348D02*
Y748821D01*
G01X138190Y724412D02*
G03X142127Y728349I0J3937D01*
G01X156102Y712600D02*
G03X160039Y716537I0J3937D01*
G01Y740947D02*
Y716537D01*
G01X146064Y752758D02*
X230906D01*
G01X146064D02*
G03X142127Y748821I0J-3937D01*
G01X180905Y744884D02*
G03Y752758I0J3937D01*
G01X163976Y744884D02*
G03X160039Y740947I0J-3937D01*
G01X223031Y744884D02*
X163976D01*
G01X142127Y862994D02*
Y883467D01*
G01X138190Y859058D02*
G03X142127Y862995I0J3937D01*
G01X180905Y879530D02*
G03Y887404I0J3937D01*
G01X156102Y847246D02*
G03X160039Y851183I0J3937D01*
G01Y875593D02*
Y851183D01*
G01X163976Y879530D02*
G03X160039Y875593I0J-3937D01*
G01X223031Y879530D02*
X163976D01*
G01X146064Y887404D02*
X230906D01*
G01X146064D02*
G03X142127Y883467I0J-3937D01*
G01X206102Y79528D02*
G03Y71654I0J-3937D01*
G01X226969Y67717D02*
G03X223031Y71654I-3937J0D01*
G01X226969Y43307D02*
Y67717D01*
G01Y43307D02*
G03X230906Y39370I3937J0D01*
G01X282283D02*
X230906D01*
G01X234843Y75591D02*
G03X230906Y79528I-3937J0D01*
G01X196309Y122835D02*
G03Y130709I0J3937D01*
G01X221506D02*
G03Y122835I0J-3937D01*
G01X234843Y210237D02*
G03X230906Y214174I-3937J0D01*
G01X206102D02*
G03Y206300I0J-3937D01*
G01X226969Y202363D02*
G03X223031Y206300I-3937J0D01*
G01X226969Y177953D02*
Y202363D01*
G01Y177953D02*
G03X230906Y174016I3937J0D01*
G01X282283D02*
X230906D01*
G01X196309Y257481D02*
G03Y265355I0J3937D01*
G01X221506D02*
G03Y257481I0J-3937D01*
G01X226969Y312599D02*
G03X230906Y308662I3937J0D01*
G01X282283D02*
X230906D01*
G01X234843Y344883D02*
G03X230906Y348820I-3937J0D01*
G01X206102D02*
G03Y340946I0J-3937D01*
G01X226969Y337009D02*
G03X223031Y340946I-3937J0D01*
G01X226969Y312599D02*
Y337009D01*
G01X196309Y392127D02*
G03Y400001I0J3937D01*
G01X221506D02*
G03Y392127I0J-3937D01*
G01X226969Y447245D02*
Y471655D01*
G01Y447245D02*
G03X230906Y443308I3937J0D01*
G01X282283D02*
X230906D01*
G01X234843Y479529D02*
G03X230906Y483466I-3937J0D01*
G01X206102D02*
G03Y475592I0J-3937D01*
G01X226969Y471655D02*
G03X223031Y475592I-3937J0D01*
G01X196309Y526773D02*
G03Y534647I0J3937D01*
G01X221506D02*
G03Y526773I0J-3937D01*
G01X226969Y581891D02*
Y606301D01*
G01Y581891D02*
G03X230906Y577954I3937J0D01*
G01X282283D02*
X230906D01*
G01X234843Y614175D02*
G03X230906Y618112I-3937J0D01*
G01X206102D02*
G03Y610238I0J-3937D01*
G01X226969Y606301D02*
G03X223031Y610238I-3937J0D01*
G01X196309Y661419D02*
G03Y669293I0J3937D01*
G01X221506D02*
G03Y661419I0J-3937D01*
G01X226969Y716537D02*
Y740947D01*
G01Y716537D02*
G03X230906Y712600I3937J0D01*
G01X282283D02*
X230906D01*
G01X234843Y748821D02*
G03X230906Y752758I-3937J0D01*
G01X206102D02*
G03Y744884I0J-3937D01*
G01X226969Y740947D02*
G03X223031Y744884I-3937J0D01*
G01X196309Y796065D02*
G03Y803939I0J3937D01*
G01X221506D02*
G03Y796065I0J-3937D01*
G01X206102Y887404D02*
G03Y879530I0J-3937D01*
G01X226969Y875593D02*
G03X223031Y879530I-3937J0D01*
G01X226969Y851183D02*
Y875593D01*
G01Y851183D02*
G03X230906Y847246I3937J0D01*
G01X282283D02*
X230906D01*
G01X234843Y883467D02*
G03X230906Y887404I-3937J0D01*
G01X266339Y55118D02*
Y75591D01*
G01X262402Y51181D02*
G03X266339Y55118I0J3937D01*
G01X238780Y51181D02*
X262402D01*
G01X234843Y55118D02*
G03X238780Y51181I3937J0D01*
G01X234843Y75591D02*
Y55118D01*
G01X270276Y79528D02*
X355119D01*
G01X270276D02*
G03X266339Y75591I0J-3937D01*
G01X270276Y214174D02*
X355119D01*
G01X270276D02*
G03X266339Y210237I0J-3937D01*
G01Y189764D02*
Y210237D01*
G01X262402Y185827D02*
G03X266339Y189764I0J3937D01*
G01X238780Y185827D02*
X262402D01*
G01X234843Y189764D02*
G03X238780Y185827I3937J0D01*
G01X234843Y210237D02*
Y189764D01*
G01X270276Y348820D02*
X355119D01*
G01X270276D02*
G03X266339Y344883I0J-3937D01*
G01Y324410D02*
Y344883D01*
G01X262402Y320473D02*
G03X266339Y324410I0J3937D01*
G01X238780Y320473D02*
X262402D01*
G01X234843Y324410D02*
G03X238780Y320473I3937J0D01*
G01X234843Y344883D02*
Y324410D01*
G01X270276Y483466D02*
X355119D01*
G01X270276D02*
G03X266339Y479529I0J-3937D01*
G01Y459056D02*
Y479529D01*
G01X262402Y455119D02*
G03X266339Y459056I0J3937D01*
G01X238780Y455119D02*
X262402D01*
G01X234843Y459057D02*
G03X238780Y455120I3937J0D01*
G01X234843Y479529D02*
Y459056D01*
G01X266339Y593702D02*
Y614175D01*
G01X262402Y589765D02*
G03X266339Y593702I0J3937D01*
G01X238780Y589765D02*
X262402D01*
G01X234843Y593703D02*
G03X238780Y589766I3937J0D01*
G01X234843Y614175D02*
Y593702D01*
G01X270276Y618112D02*
X355119D01*
G01X270276D02*
G03X266339Y614175I0J-3937D01*
G01Y728348D02*
Y748821D01*
G01X262402Y724411D02*
G03X266339Y728348I0J3937D01*
G01X238780Y724411D02*
X262402D01*
G01X234843Y728349D02*
G03X238780Y724412I3937J0D01*
G01X234843Y748821D02*
Y728348D01*
G01X270276Y752758D02*
X355119D01*
G01X270276D02*
G03X266339Y748821I0J-3937D01*
G01Y862994D02*
Y883467D01*
G01X262402Y859057D02*
G03X266339Y862994I0J3937D01*
G01X238780Y859057D02*
X262402D01*
G01X234843Y862995D02*
G03X238780Y859058I3937J0D01*
G01X234843Y883467D02*
Y862994D01*
G01X270276Y887404D02*
X355119D01*
G01X270276D02*
G03X266339Y883467I0J-3937D01*
G01X306969Y19685D02*
G03X296969I-5000J0D01*
G01D02*
G03X306969I5000J0D01*
G01X325788Y39370D02*
G03Y47244I0J3937D01*
G01Y71654D02*
G03Y79528I0J3937D01*
G01X325591Y71654D02*
X325788D01*
G01X325591Y47244D02*
Y71654D01*
G01X325788Y47244D02*
X325591D01*
G01X282283Y39370D02*
G03X286220Y43307I0J3937D01*
G01Y63780D02*
Y43307D01*
G01X290157Y67717D02*
G03X286220Y63780I0J-3937D01*
G01X313780Y67717D02*
X290157D01*
G01X317717Y63780D02*
G03X313780Y67717I-3937J0D01*
G01X317717Y43307D02*
Y63780D01*
G01Y43307D02*
G03X321654Y39370I3937J0D01*
G01X406496D02*
X321654D01*
G01X307265Y99213D02*
G03X317343I5039J0D01*
G01D02*
G03X307265I-5039J0D01*
G01X306969Y154331D02*
G03X296969I-5000J0D01*
G01D02*
G03X306969I5000J0D01*
G01X325788Y174016D02*
G03Y181890I0J3937D01*
G01Y206300D02*
G03Y214174I0J3937D01*
G01X325591Y206300D02*
X325788D01*
G01X325591Y181890D02*
Y206300D01*
G01X325788Y181890D02*
X325591D01*
G01X282283Y174016D02*
G03X286220Y177953I0J3937D01*
G01Y198426D02*
Y177953D01*
G01X290157Y202363D02*
G03X286220Y198426I0J-3937D01*
G01X313780Y202363D02*
X290157D01*
G01X317717Y198426D02*
G03X313780Y202363I-3937J0D01*
G01X317717Y177953D02*
Y198426D01*
G01Y177953D02*
G03X321654Y174016I3937J0D01*
G01X406496D02*
X321654D01*
G01X307265Y233859D02*
G03X317343I5039J0D01*
G01D02*
G03X307265I-5039J0D01*
G01X325788Y308662D02*
G03Y316536I0J3937D01*
G01X306969Y288977D02*
G03X296969I-5000J0D01*
G01D02*
G03X306969I5000J0D01*
G01X282283Y308662D02*
G03X286220Y312599I0J3937D01*
G01X317717D02*
G03X321654Y308662I3937J0D01*
G01X406496D02*
X321654D01*
G01X325788Y340946D02*
G03Y348820I0J3937D01*
G01X325591Y340946D02*
X325788D01*
G01X325591Y316536D02*
Y340946D01*
G01X325788Y316536D02*
X325591D01*
G01X286220Y333072D02*
Y312599D01*
G01X290157Y337009D02*
G03X286220Y333072I0J-3937D01*
G01X313780Y337009D02*
X290157D01*
G01X317717Y333072D02*
G03X313780Y337009I-3937J0D01*
G01X317717Y312599D02*
Y333072D01*
G01X307265Y368505D02*
G03X317343I5039J0D01*
G01D02*
G03X307265I-5039J0D01*
G01X325788Y443308D02*
G03Y451182I0J3937D01*
G01X325591D02*
Y475592D01*
G01X325788Y451182D02*
X325591D01*
G01X306969Y423623D02*
G03X296969I-5000J0D01*
G01D02*
G03X306969I5000J0D01*
G01X282283Y443308D02*
G03X286220Y447245I0J3937D01*
G01Y467718D02*
Y447245D01*
G01X317717D02*
Y467718D01*
G01Y447245D02*
G03X321654Y443308I3937J0D01*
G01X406496D02*
X321654D01*
G01X307265Y503151D02*
G03X317343I5039J0D01*
G01X325788Y475592D02*
G03Y483466I0J3937D01*
G01X325591Y475592D02*
X325788D01*
G01X290157Y471655D02*
G03X286220Y467718I0J-3937D01*
G01X313780Y471655D02*
X290157D01*
G01X317717Y467718D02*
G03X313780Y471655I-3937J0D01*
G01X317343Y503151D02*
G03X307265I-5039J0D01*
G01X325788Y577954D02*
G03Y585828I0J3937D01*
G01X325591D02*
Y610238D01*
G01X325788Y585828D02*
X325591D01*
G01X306969Y558269D02*
G03X296969I-5000J0D01*
G01D02*
G03X306969I5000J0D01*
G01X282283Y577954D02*
G03X286220Y581891I0J3937D01*
G01Y602364D02*
Y581891D01*
G01X317717D02*
Y602364D01*
G01Y581891D02*
G03X321654Y577954I3937J0D01*
G01X406496D02*
X321654D01*
G01X307265Y637797D02*
G03X317343I5039J0D01*
G01D02*
G03X307265I-5039J0D01*
G01X325788Y610238D02*
G03Y618112I0J3937D01*
G01X325591Y610238D02*
X325788D01*
G01X290157Y606301D02*
G03X286220Y602364I0J-3937D01*
G01X313780Y606301D02*
X290157D01*
G01X317717Y602364D02*
G03X313780Y606301I-3937J0D01*
G01X296969Y692915D02*
G03X306969I5000J0D01*
G01X325788Y712600D02*
G03Y720474I0J3937D01*
G01X325591D02*
Y744884D01*
G01X325788Y720474D02*
X325591D01*
G01X306969Y692915D02*
G03X296969I-5000J0D01*
G01X282283Y712600D02*
G03X286220Y716537I0J3937D01*
G01Y737010D02*
Y716537D01*
G01X290157Y740947D02*
G03X286220Y737010I0J-3937D01*
G01X317717Y737011D02*
G03X313780Y740947I-3937J-1D01*
G01X317717Y716537D02*
Y737010D01*
G01Y716537D02*
G03X321654Y712600I3937J0D01*
G01X406496D02*
X321654D01*
G01X307265Y772443D02*
G03X317343I5039J0D01*
G01D02*
G03X307265I-5039J0D01*
G01X325788Y744884D02*
G03Y752758I0J3937D01*
G01X325591Y744884D02*
X325788D01*
G01X313780Y740947D02*
X290157D01*
G01X306969Y827561D02*
G03X296969I-5000J0D01*
G01D02*
G03X306969I5000J0D01*
G01X325788Y847246D02*
G03Y855120I0J3937D01*
G01Y879530D02*
G03Y887404I0J3937D01*
G01X325591Y879530D02*
X325788D01*
G01X325591Y855120D02*
Y879530D01*
G01X325788Y855120D02*
X325591D01*
G01X282283Y847246D02*
G03X286220Y851183I0J3937D01*
G01Y871656D02*
Y851183D01*
G01X290157Y875593D02*
G03X286220Y871656I0J-3937D01*
G01X313780Y875593D02*
X290157D01*
G01X317717Y871657D02*
G03X313780Y875593I-3937J-1D01*
G01X317717Y851183D02*
Y871656D01*
G01Y851183D02*
G03X321654Y847246I3937J0D01*
G01X406496D02*
X321654D01*
G01X307265Y907089D02*
G03X317343I5039J0D01*
G01D02*
G03X307265I-5039J0D01*
G01X362993Y51181D02*
X386615D01*
G01X359056Y55118D02*
G03X362993Y51181I3937J0D01*
G01X359056Y75591D02*
Y55118D01*
G01X350985Y71654D02*
X351182D01*
G01X350985Y47244D02*
X351182D01*
G01X350985D02*
G03Y39370I0J-3937D01*
G01Y79528D02*
G03Y71654I0J-3937D01*
G01X351182D02*
Y47244D01*
G01X359056Y75591D02*
G03X355119Y79528I-3937J0D01*
G01X362993Y185827D02*
X386615D01*
G01X359056Y189764D02*
G03X362993Y185827I3937J0D01*
G01X359056Y210237D02*
Y189764D01*
G01Y210237D02*
G03X355119Y214174I-3937J0D01*
G01X350985Y206300D02*
X351182D01*
G01X350985Y181890D02*
X351182D01*
G01X350985D02*
G03Y174016I0J-3937D01*
G01Y214174D02*
G03Y206300I0J-3937D01*
G01X351182D02*
Y181890D01*
G01X350985Y316536D02*
G03Y308662I0J-3937D01*
G01X362993Y320473D02*
X386615D01*
G01X359056Y324410D02*
G03X362993Y320473I3937J0D01*
G01X359056Y344883D02*
Y324410D01*
G01Y344883D02*
G03X355119Y348820I-3937J0D01*
G01X350985Y340946D02*
X351182D01*
G01X350985Y316536D02*
X351182D01*
G01X350985Y348820D02*
G03Y340946I0J-3937D01*
G01X351182D02*
Y316536D01*
G01X350985Y451182D02*
X351182D01*
G01X350985D02*
G03Y443308I0J-3937D01*
G01X351182Y475592D02*
Y451182D01*
G01X362993Y455119D02*
X386615D01*
G01X359056Y459056D02*
G03X362993Y455119I3937J0D01*
G01X359056Y479529D02*
Y459056D01*
G01Y479529D02*
G03X355119Y483466I-3937J0D01*
G01X350985Y475592D02*
X351182D01*
G01X350985Y483466D02*
G03Y475592I0J-3937D01*
G01X362993Y589765D02*
X386615D01*
G01X359056Y593702D02*
G03X362993Y589765I3937J0D01*
G01X359056Y614175D02*
Y593702D01*
G01X350985Y585828D02*
X351182D01*
G01X350985D02*
G03Y577954I0J-3937D01*
G01X351182Y610238D02*
Y585828D01*
G01X359056Y614175D02*
G03X355119Y618112I-3937J0D01*
G01X350985Y610238D02*
X351182D01*
G01X350985Y618112D02*
G03Y610238I0J-3937D01*
G01X362993Y724411D02*
X386615D01*
G01X359056Y728349D02*
G03X362993Y724412I3937J0D01*
G01X359056Y748821D02*
Y728348D01*
G01X350985Y720474D02*
X351182D01*
G01X350985D02*
G03Y712600I0J-3937D01*
G01X351182Y744884D02*
Y720474D01*
G01X359056Y748821D02*
G03X355119Y752758I-3937J0D01*
G01X350985Y744884D02*
X351182D01*
G01X350985Y752758D02*
G03Y744884I0J-3937D01*
G01X362993Y859057D02*
X386615D01*
G01X359056Y862995D02*
G03X362993Y859058I3937J0D01*
G01X359056Y883467D02*
Y862994D01*
G01X350985Y879530D02*
X351182D01*
G01X350985Y855120D02*
X351182D01*
G01X350985D02*
G03Y847246I0J-3937D01*
G01Y887404D02*
G03Y879530I0J-3937D01*
G01X351182D02*
Y855120D01*
G01X359056Y883467D02*
G03X355119Y887404I-3937J0D01*
G01X390552Y55118D02*
Y75591D01*
G01X386615Y51181D02*
G03X390552Y55118I0J3937D01*
G01X406496Y39370D02*
G03X410433Y43307I0J3937D01*
G01Y63780D02*
Y43307D01*
G01X414370Y67717D02*
G03X410433Y63780I0J-3937D01*
G01X437992Y67717D02*
X414370D01*
G01X394489Y79528D02*
X479331D01*
G01X394489D02*
G03X390552Y75591I0J-3937D01*
G01X387894Y122835D02*
G03Y130709I0J3937D01*
G01X413091D02*
G03Y122835I0J-3937D01*
G01X394489Y214174D02*
X479331D01*
G01X394489D02*
G03X390552Y210237I0J-3937D01*
G01Y189764D02*
Y210237D01*
G01X386615Y185827D02*
G03X390552Y189764I0J3937D01*
G01X406496Y174016D02*
G03X410433Y177953I0J3937D01*
G01Y198426D02*
Y177953D01*
G01X414370Y202363D02*
G03X410433Y198426I0J-3937D01*
G01X437992Y202363D02*
X414370D01*
G01X387894Y257481D02*
G03Y265355I0J3937D01*
G01X413091D02*
G03Y257481I0J-3937D01*
G01X406496Y308662D02*
G03X410433Y312599I0J3937D01*
G01X394489Y348820D02*
X479331D01*
G01X394489D02*
G03X390552Y344883I0J-3937D01*
G01Y324410D02*
Y344883D01*
G01X386615Y320473D02*
G03X390552Y324410I0J3937D01*
G01X410433Y333072D02*
Y312599D01*
G01X414370Y337009D02*
G03X410433Y333072I0J-3937D01*
G01X437992Y337009D02*
X414370D01*
G01X387894Y392127D02*
G03Y400001I0J3937D01*
G01X413091D02*
G03Y392127I0J-3937D01*
G01X406496Y443308D02*
G03X410433Y447245I0J3937D01*
G01Y467718D02*
Y447245D01*
G01X394489Y483466D02*
X479331D01*
G01X394489D02*
G03X390552Y479529I0J-3937D01*
G01Y459056D02*
Y479529D01*
G01X386615Y455119D02*
G03X390552Y459056I0J3937D01*
G01X414370Y471655D02*
G03X410433Y467718I0J-3937D01*
G01X437992Y471655D02*
X414370D01*
G01X387894Y526773D02*
G03Y534647I0J3937D01*
G01X413091D02*
G03Y526773I0J-3937D01*
G01X390552Y593702D02*
Y614175D01*
G01X386615Y589765D02*
G03X390552Y593702I0J3937D01*
G01X406496Y577954D02*
G03X410433Y581891I0J3937D01*
G01Y602364D02*
Y581891D01*
G01X394489Y618112D02*
X479331D01*
G01X394489D02*
G03X390552Y614175I0J-3937D01*
G01X414370Y606301D02*
G03X410433Y602364I0J-3937D01*
G01X437992Y606301D02*
X414370D01*
G01X387894Y661419D02*
G03Y669293I0J3937D01*
G01X413091D02*
G03Y661419I0J-3937D01*
G01X390552Y728348D02*
Y748821D01*
G01X386615Y724412D02*
G03X390552Y728349I0J3937D01*
G01X406496Y712600D02*
G03X410433Y716537I0J3937D01*
G01Y737010D02*
Y716537D01*
G01X414370Y740947D02*
G03X410433Y737010I0J-3937D01*
G01X394489Y752758D02*
X479331D01*
G01X394489D02*
G03X390552Y748821I0J-3937D01*
G01X437992Y740947D02*
X414370D01*
G01X387894Y796065D02*
G03Y803939I0J3937D01*
G01X413091D02*
G03Y796065I0J-3937D01*
G01X390552Y862994D02*
Y883467D01*
G01X386615Y859058D02*
G03X390552Y862995I0J3937D01*
G01X406496Y847246D02*
G03X410433Y851183I0J3937D01*
G01Y871656D02*
Y851183D01*
G01X414370Y875593D02*
G03X410433Y871656I0J-3937D01*
G01X437992Y875593D02*
X414370D01*
G01X394489Y887404D02*
X479331D01*
G01X394489D02*
G03X390552Y883467I0J-3937D01*
G01X450000Y47244D02*
X449803D01*
G01X450000Y71654D02*
X449803D01*
G01X450000D02*
G03Y79528I0J3937D01*
G01Y39370D02*
G03Y47244I0J3937D01*
G01X449803D02*
Y71654D01*
G01X441929Y63780D02*
G03X437992Y67717I-3937J0D01*
G01X441929Y43307D02*
Y63780D01*
G01Y43307D02*
G03X445866Y39370I3937J0D01*
G01X530709D02*
X445866D01*
G01X450000Y181890D02*
X449803D01*
G01X450000Y206300D02*
X449803D01*
G01X450000D02*
G03Y214174I0J3937D01*
G01Y174016D02*
G03Y181890I0J3937D01*
G01X449803D02*
Y206300D01*
G01X441929Y198426D02*
G03X437992Y202363I-3937J0D01*
G01X441929Y177953D02*
Y198426D01*
G01Y177953D02*
G03X445866Y174016I3937J0D01*
G01X530709D02*
X445866D01*
G01X450000Y308662D02*
G03Y316536I0J3937D01*
G01X441929Y312599D02*
G03X445866Y308662I3937J0D01*
G01X530709D02*
X445866D01*
G01X450000Y316536D02*
X449803D01*
G01X450000Y340946D02*
X449803D01*
G01X450000D02*
G03Y348820I0J3937D01*
G01X449803Y316536D02*
Y340946D01*
G01X441929Y333072D02*
G03X437992Y337009I-3937J0D01*
G01X441929Y312599D02*
Y333072D01*
G01X450000Y451182D02*
X449803D01*
G01X450000Y443308D02*
G03Y451182I0J3937D01*
G01X449803D02*
Y475592D01*
G01X441929Y447245D02*
Y467718D01*
G01Y447245D02*
G03X445866Y443308I3937J0D01*
G01X530709D02*
X445866D01*
G01X450000Y475592D02*
X449803D01*
G01X450000D02*
G03Y483466I0J3937D01*
G01X441929Y467718D02*
G03X437992Y471655I-3937J0D01*
G01X450000Y585828D02*
X449803D01*
G01X450000Y577954D02*
G03Y585828I0J3937D01*
G01X449803D02*
Y610238D01*
G01X441929Y581891D02*
Y602364D01*
G01Y581891D02*
G03X445866Y577954I3937J0D01*
G01X530709D02*
X445866D01*
G01X450000Y610238D02*
X449803D01*
G01X450000D02*
G03Y618112I0J3937D01*
G01X441929Y602364D02*
G03X437992Y606301I-3937J0D01*
G01X450000Y720474D02*
X449803D01*
G01X450000Y712600D02*
G03Y720474I0J3937D01*
G01X449803D02*
Y744884D01*
G01X441929Y737010D02*
G03X437992Y740947I-3937J0D01*
G01X441929Y716537D02*
Y737010D01*
G01Y716537D02*
G03X445866Y712600I3937J0D01*
G01X530709D02*
X445866D01*
G01X450000Y744884D02*
X449803D01*
G01X450000D02*
G03Y752758I0J3937D01*
G01Y855120D02*
X449803D01*
G01X450000Y879530D02*
X449803D01*
G01X450000D02*
G03Y887404I0J3937D01*
G01Y847246D02*
G03Y855120I0J3937D01*
G01X449803D02*
Y879530D01*
G01X441929Y871656D02*
G03X437992Y875593I-3937J0D01*
G01X441929Y851183D02*
Y871656D01*
G01Y851183D02*
G03X445866Y847246I3937J0D01*
G01X530709D02*
X445866D01*
G01X493720Y19685D02*
G03X483642I-5039J0D01*
G01D02*
G03X493720I5039J0D01*
G01X514765Y55118D02*
Y75591D01*
G01X510828Y51181D02*
G03X514765Y55118I0J3937D01*
G01X487205Y51181D02*
X510828D01*
G01X483269Y55118D02*
G03X487205Y51182I3937J1D01*
G01X483268Y75591D02*
Y55118D01*
G01X475197Y79528D02*
G03Y71654I0J-3937D01*
G01Y47244D02*
G03Y39370I0J-3937D01*
G01X475394Y47244D02*
X475197D01*
G01X475394Y71654D02*
Y47244D01*
G01X475197Y71654D02*
X475394D01*
G01X494017Y99213D02*
G03X504017I5000J0D01*
G01D02*
G03X494017I-5000J0D01*
G01X518702Y79528D02*
X570079D01*
G01X518702D02*
G03X514765Y75591I0J-3937D01*
G01X483268D02*
G03X479331Y79528I-3937J0D01*
G01X493720Y154331D02*
G03X483642I-5039J0D01*
G01D02*
G03X493720I5039J0D01*
G01X518702Y214174D02*
X570079D01*
G01X518702D02*
G03X514765Y210237I0J-3937D01*
G01Y189764D02*
Y210237D01*
G01X510828Y185827D02*
G03X514765Y189764I0J3937D01*
G01X487205Y185827D02*
X510828D01*
G01X483269Y189764D02*
G03X487205Y185828I3937J1D01*
G01X483268Y210237D02*
Y189764D01*
G01Y210237D02*
G03X479331Y214174I-3937J0D01*
G01X475197D02*
G03Y206300I0J-3937D01*
G01Y181890D02*
G03Y174016I0J-3937D01*
G01X475394Y181890D02*
X475197D01*
G01X475394Y206300D02*
Y181890D01*
G01X475197Y206300D02*
X475394D01*
G01X494017Y233859D02*
G03X504017I5000J0D01*
G01D02*
G03X494017I-5000J0D01*
G01X475197Y316536D02*
G03Y308662I0J-3937D01*
G01X493720Y288977D02*
G03X483642I-5039J0D01*
G01D02*
G03X493720I5039J0D01*
G01X518702Y348820D02*
X570079D01*
G01X518702D02*
G03X514765Y344883I0J-3937D01*
G01Y324410D02*
Y344883D01*
G01X510828Y320473D02*
G03X514765Y324410I0J3937D01*
G01X487205Y320473D02*
X510828D01*
G01X483269Y324410D02*
G03X487205Y320474I3937J1D01*
G01X483268Y344883D02*
Y324410D01*
G01Y344883D02*
G03X479331Y348820I-3937J0D01*
G01X475197D02*
G03Y340946I0J-3937D01*
G01X475394Y316536D02*
X475197D01*
G01X475394Y340946D02*
Y316536D01*
G01X475197Y340946D02*
X475394D01*
G01X494017Y368505D02*
G03X504017I5000J0D01*
G01D02*
G03X494017I-5000J0D01*
G01X475197Y451182D02*
G03Y443308I0J-3937D01*
G01X475394Y451182D02*
X475197D01*
G01X475394Y475592D02*
Y451182D01*
G01X493720Y423623D02*
G03X483642I-5039J0D01*
G01D02*
G03X493720I5039J0D01*
G01X494017Y503151D02*
G03X504017I5000J0D01*
G01X518702Y483466D02*
X570079D01*
G01X518702D02*
G03X514765Y479529I0J-3937D01*
G01Y459056D02*
Y479529D01*
G01X510828Y455120D02*
G03X514765Y459057I0J3937D01*
G01X487205Y455119D02*
X510828D01*
G01X483269Y459056D02*
G03X487205Y455120I3937J1D01*
G01X483268Y479529D02*
Y459056D01*
G01Y479529D02*
G03X479331Y483466I-3937J0D01*
G01X475197D02*
G03Y475592I0J-3937D01*
G01D02*
X475394D01*
G01X504017Y503151D02*
G03X494017I-5000J0D01*
G01X514765Y593702D02*
Y614175D01*
G01X510828Y589766D02*
G03X514765Y593703I0J3937D01*
G01X487205Y589765D02*
X510828D01*
G01X483269Y593702D02*
G03X487205Y589766I3937J1D01*
G01X483268Y614175D02*
Y593702D01*
G01X475197Y585828D02*
G03Y577954I0J-3937D01*
G01X475394Y585828D02*
X475197D01*
G01X475394Y610238D02*
Y585828D01*
G01X493720Y558269D02*
G03X483642I-5039J0D01*
G01D02*
G03X493720I5039J0D01*
G01X494017Y637797D02*
G03X504017I5000J0D01*
G01D02*
G03X494017I-5000J0D01*
G01X518702Y618112D02*
X570079D01*
G01X518702D02*
G03X514765Y614175I0J-3937D01*
G01X483268D02*
G03X479331Y618112I-3937J0D01*
G01X475197D02*
G03Y610238I0J-3937D01*
G01D02*
X475394D01*
G01X483642Y692915D02*
G03X493720I5039J0D01*
G01X514765Y728348D02*
Y748821D01*
G01X510828Y724412D02*
G03X514765Y728349I0J3937D01*
G01X487205Y724411D02*
X510828D01*
G01X483269Y728348D02*
G03X487205Y724412I3937J1D01*
G01X483268Y748821D02*
Y728348D01*
G01X475197Y720474D02*
G03Y712600I0J-3937D01*
G01X475394Y720474D02*
X475197D01*
G01X475394Y744884D02*
Y720474D01*
G01X493720Y692915D02*
G03X483642I-5039J0D01*
G01X494017Y772443D02*
G03X504017I5000J0D01*
G01D02*
G03X494017I-5000J0D01*
G01X518702Y752758D02*
X570079D01*
G01X518702D02*
G03X514765Y748821I0J-3937D01*
G01X483268D02*
G03X479331Y752758I-3937J0D01*
G01X475197D02*
G03Y744884I0J-3937D01*
G01D02*
X475394D01*
G01X493720Y827561D02*
G03X483642I-5039J0D01*
G01D02*
G03X493720I5039J0D01*
G01X514765Y862994D02*
Y883467D01*
G01X510828Y859058D02*
G03X514765Y862995I0J3937D01*
G01X487205Y859057D02*
X510828D01*
G01X483269Y862994D02*
G03X487205Y859058I3937J1D01*
G01X483268Y883467D02*
Y862994D01*
G01X475197Y887404D02*
G03Y879530I0J-3937D01*
G01Y855120D02*
G03Y847246I0J-3937D01*
G01X475394Y855120D02*
X475197D01*
G01X475394Y879530D02*
Y855120D01*
G01X475197Y879530D02*
X475394D01*
G01X494017Y907089D02*
G03X504017I5000J0D01*
G01D02*
G03X494017I-5000J0D01*
G01X518702Y887404D02*
X570079D01*
G01X518702D02*
G03X514765Y883467I0J-3937D01*
G01X483268D02*
G03X479331Y887404I-3937J0D01*
G01X530709Y39370D02*
G03X534646Y43307I0J3937D01*
G01Y63780D02*
Y43307D01*
G01X538583Y67717D02*
G03X534646Y63780I0J-3937D01*
G01X562205Y67717D02*
X538583D01*
G01X566142Y63780D02*
G03X562205Y67717I-3937J0D01*
G01X566142Y43307D02*
Y63780D01*
G01Y43307D02*
G03X570079Y39370I3937J0D01*
G01X530709Y174016D02*
G03X534646Y177953I0J3937D01*
G01Y198426D02*
Y177953D01*
G01X538583Y202363D02*
G03X534646Y198426I0J-3937D01*
G01X562205Y202363D02*
X538583D01*
G01X566142Y198426D02*
G03X562205Y202363I-3937J0D01*
G01X566142Y177953D02*
Y198426D01*
G01Y177953D02*
G03X570079Y174016I3937J0D01*
G01X530709Y308662D02*
G03X534646Y312599I0J3937D01*
G01Y333072D02*
Y312599D01*
G01X538583Y337009D02*
G03X534646Y333072I0J-3937D01*
G01X562205Y337009D02*
X538583D01*
G01X566142Y333072D02*
G03X562205Y337009I-3937J0D01*
G01X566142Y312599D02*
Y333072D01*
G01Y312599D02*
G03X570079Y308662I3937J0D01*
G01X530709Y443308D02*
G03X534646Y447245I0J3937D01*
G01Y467718D02*
Y447245D01*
G01X566142D02*
Y467718D01*
G01Y447245D02*
G03X570079Y443308I3937J0D01*
G01X538583Y471655D02*
G03X534646Y467718I0J-3937D01*
G01X562205Y471655D02*
X538583D01*
G01X566142Y467718D02*
G03X562205Y471655I-3937J0D01*
G01X530709Y577954D02*
G03X534646Y581891I0J3937D01*
G01Y602364D02*
Y581891D01*
G01X566142D02*
Y602364D01*
G01Y581891D02*
G03X570079Y577954I3937J0D01*
G01X538583Y606301D02*
G03X534646Y602364I0J-3937D01*
G01X562205Y606301D02*
X538583D01*
G01X566142Y602364D02*
G03X562205Y606301I-3937J0D01*
G01X530709Y712601D02*
G03X534646Y716538I0J3937D01*
G01Y737010D02*
Y716537D01*
G01X538583Y740947D02*
G03X534646Y737010I0J-3937D01*
G01X566142D02*
G03X562205Y740947I-3937J0D01*
G01X566142Y716537D02*
Y737010D01*
G01Y716537D02*
G03X570079Y712600I3937J0D01*
G01X562205Y740947D02*
X538583D01*
G01X530709Y847247D02*
G03X534646Y851184I0J3937D01*
G01Y871656D02*
Y851183D01*
G01X538583Y875593D02*
G03X534646Y871656I0J-3937D01*
G01X562205Y875593D02*
X538583D01*
G01X566142Y871656D02*
G03X562205Y875593I-3937J0D01*
G01X566142Y851183D02*
Y871656D01*
G01Y851183D02*
G03X570079Y847246I3937J0D01*
G01X577954Y47244D02*
X637009D01*
G01X574016Y51181D02*
G03X577954Y47244I3937J0D01*
G01X574016Y75591D02*
Y51181D01*
G01X594883Y39370D02*
G03Y47244I0J3937D01*
G01X654921Y39370D02*
X570079D01*
G01X574016Y75591D02*
G03X570079Y79528I-3937J0D01*
G01X604676Y130709D02*
G03Y122835I0J-3937D01*
G01X579479D02*
G03Y130709I0J3937D01*
G01X577954Y181890D02*
X637009D01*
G01X574016Y185827D02*
G03X577954Y181890I3937J0D01*
G01X574016Y210237D02*
Y185827D01*
G01Y210237D02*
G03X570079Y214174I-3937J0D01*
G01X594883Y174016D02*
G03Y181890I0J3937D01*
G01X654921Y174016D02*
X570079D01*
G01X604676Y265355D02*
G03Y257481I0J-3937D01*
G01X579479D02*
G03Y265355I0J3937D01*
G01X594883Y308662D02*
G03Y316536I0J3937D01*
G01X654921Y308662D02*
X570079D01*
G01X577954Y316536D02*
X637009D01*
G01X574016Y320473D02*
G03X577954Y316536I3937J0D01*
G01X574016Y344883D02*
Y320473D01*
G01Y344883D02*
G03X570079Y348820I-3937J0D01*
G01X604676Y400001D02*
G03Y392127I0J-3937D01*
G01X579479D02*
G03Y400001I0J3937D01*
G01X577954Y451182D02*
X637009D01*
G01X574016Y455120D02*
G03X577954Y451183I3937J0D01*
G01X594883Y443308D02*
G03Y451182I0J3937D01*
G01X654921Y443308D02*
X570079D01*
G01X574016Y479529D02*
Y455119D01*
G01Y479529D02*
G03X570079Y483466I-3937J0D01*
G01X604676Y534647D02*
G03Y526773I0J-3937D01*
G01X579479D02*
G03Y534647I0J3937D01*
G01X577954Y585828D02*
X637009D01*
G01X574016Y589766D02*
G03X577954Y585829I3937J0D01*
G01X574016Y614175D02*
Y589765D01*
G01X594883Y577954D02*
G03Y585828I0J3937D01*
G01X654921Y577954D02*
X570079D01*
G01X574016Y614175D02*
G03X570079Y618112I-3937J0D01*
G01X604676Y669293D02*
G03Y661419I0J-3937D01*
G01X579479D02*
G03Y669293I0J3937D01*
G01X577954Y720474D02*
X637009D01*
G01X574016Y724412D02*
G03X577954Y720475I3937J0D01*
G01X574016Y748821D02*
Y724411D01*
G01X594883Y712600D02*
G03Y720474I0J3937D01*
G01X654921Y712600D02*
X570079D01*
G01X574016Y748821D02*
G03X570079Y752758I-3937J0D01*
G01X604676Y803939D02*
G03Y796065I0J-3937D01*
G01X579479D02*
G03Y803939I0J3937D01*
G01X577954Y855120D02*
X637009D01*
G01X574016Y859058D02*
G03X577954Y855121I3937J0D01*
G01X574016Y883467D02*
Y859057D01*
G01X594883Y847246D02*
G03Y855120I0J3937D01*
G01X654921Y847246D02*
X570079D01*
G01X574016Y883467D02*
G03X570079Y887404I-3937J0D01*
G01X640946Y51181D02*
Y75591D01*
G01X637009Y47244D02*
G03X640946Y51181I0J3937D01*
G01X620080Y47244D02*
G03Y39370I0J-3937D01*
G01X654921D02*
G03X658858Y43307I0J3937D01*
G01Y63780D02*
Y43307D01*
G01X662795Y67717D02*
G03X658858Y63780I0J-3937D01*
G01X644883Y79528D02*
X727757D01*
G01X644883D02*
G03X640946Y75591I0J-3937D01*
G01X644883Y214174D02*
X727757D01*
G01X644883D02*
G03X640946Y210237I0J-3937D01*
G01Y185827D02*
Y210237D01*
G01X637009Y181890D02*
G03X640946Y185827I0J3937D01*
G01X620080Y181890D02*
G03Y174016I0J-3937D01*
G01X654921D02*
G03X658858Y177953I0J3937D01*
G01Y198426D02*
Y177953D01*
G01X662795Y202363D02*
G03X658858Y198426I0J-3937D01*
G01X620080Y316536D02*
G03Y308662I0J-3937D01*
G01X654921D02*
G03X658858Y312599I0J3937D01*
G01X644883Y348820D02*
X727757D01*
G01X644883D02*
G03X640946Y344883I0J-3937D01*
G01Y320473D02*
Y344883D01*
G01X637009Y316536D02*
G03X640946Y320473I0J3937D01*
G01X658858Y333072D02*
Y312599D01*
G01X662795Y337009D02*
G03X658858Y333072I0J-3937D01*
G01X637009Y451183D02*
G03X640946Y455120I0J3937D01*
G01X620080Y451182D02*
G03Y443308I0J-3937D01*
G01X654921D02*
G03X658858Y447245I0J3937D01*
G01Y467718D02*
Y447245D01*
G01X644883Y483466D02*
X727757D01*
G01X644883D02*
G03X640946Y479529I0J-3937D01*
G01Y455119D02*
Y479529D01*
G01X662795Y471655D02*
G03X658858Y467718I0J-3937D01*
G01X640946Y589765D02*
Y614175D01*
G01X637009Y585829D02*
G03X640946Y589766I0J3937D01*
G01X620080Y585828D02*
G03Y577954I0J-3937D01*
G01X654921D02*
G03X658858Y581891I0J3937D01*
G01Y602364D02*
Y581891D01*
G01X644883Y618112D02*
X727757D01*
G01X644883D02*
G03X640946Y614175I0J-3937D01*
G01X662795Y606301D02*
G03X658858Y602364I0J-3937D01*
G01X640946Y724411D02*
Y748821D01*
G01X637009Y720475D02*
G03X640946Y724412I0J3937D01*
G01X620080Y720474D02*
G03Y712600I0J-3937D01*
G01X654921D02*
G03X658858Y716537I0J3937D01*
G01Y737010D02*
Y716537D01*
G01X662795Y740947D02*
G03X658858Y737010I0J-3937D01*
G01X644883Y752758D02*
X727757D01*
G01X644883D02*
G03X640946Y748821I0J-3937D01*
G01Y859057D02*
Y883467D01*
G01X637009Y855121D02*
G03X640946Y859058I0J3937D01*
G01X620080Y855120D02*
G03Y847246I0J-3937D01*
G01X654921D02*
G03X658858Y851183I0J3937D01*
G01Y871656D02*
Y851183D01*
G01X662795Y875593D02*
G03X658858Y871656I0J-3937D01*
G01X644883Y887404D02*
X727757D01*
G01X644883D02*
G03X640946Y883467I0J-3937D01*
G01X686319Y19685D02*
G03X674902I-5708J0D01*
G01D02*
G03X686319I5708J0D01*
G01X717106D02*
G03X707106I-5000J0D01*
G01D02*
G03X717106I5000J0D01*
G01X701969Y39370D02*
G03Y47244I0J3937D01*
G01Y71654D02*
G03Y79528I0J3937D01*
G01X698228Y71654D02*
X701969D01*
G01X698228Y47244D02*
Y71654D01*
G01X701969Y47244D02*
X698228D01*
G01X686417Y67717D02*
X662795D01*
G01X690354Y63780D02*
G03X686417Y67717I-3937J0D01*
G01X690354Y43307D02*
Y63780D01*
G01Y43307D02*
G03X694291Y39370I3937J0D01*
G01X724409D02*
X694291D01*
G01X686319Y154331D02*
G03X674902I-5708J0D01*
G01D02*
G03X686319I5708J0D01*
G01X717106D02*
G03X707106I-5000J0D01*
G01D02*
G03X717106I5000J0D01*
G01X701969Y174016D02*
G03Y181890I0J3937D01*
G01Y206300D02*
G03Y214174I0J3937D01*
G01X698228Y206300D02*
X701969D01*
G01X698228Y181890D02*
Y206300D01*
G01X701969Y181890D02*
X698228D01*
G01X686417Y202363D02*
X662795D01*
G01X690354Y198426D02*
G03X686417Y202363I-3937J0D01*
G01X690354Y177953D02*
Y198426D01*
G01Y177953D02*
G03X694291Y174016I3937J0D01*
G01X724409D02*
X694291D01*
G01X701969Y308662D02*
G03Y316536I0J3937D01*
G01X686319Y288977D02*
G03X674902I-5708J0D01*
G01D02*
G03X686319I5708J0D01*
G01X717106D02*
G03X707106I-5000J0D01*
G01D02*
G03X717106I5000J0D01*
G01X690354Y312599D02*
G03X694291Y308662I3937J0D01*
G01X724409D02*
X694291D01*
G01X701969Y340946D02*
G03Y348820I0J3937D01*
G01X698228Y340946D02*
X701969D01*
G01X698228Y316536D02*
Y340946D01*
G01X701969Y316536D02*
X698228D01*
G01X686417Y337009D02*
X662795D01*
G01X690354Y333072D02*
G03X686417Y337009I-3937J0D01*
G01X690354Y312599D02*
Y333072D01*
G01X701969Y443308D02*
G03Y451182I0J3937D01*
G01X698228D02*
Y475592D01*
G01X701969Y451182D02*
X698228D01*
G01X686319Y423623D02*
G03X674902I-5708J0D01*
G01D02*
G03X686319I5708J0D01*
G01X717106D02*
G03X707106I-5000J0D01*
G01D02*
G03X717106I5000J0D01*
G01X690354Y447245D02*
Y467718D01*
G01Y447245D02*
G03X694291Y443308I3937J0D01*
G01X724409D02*
X694291D01*
G01X701969Y475592D02*
G03Y483466I0J3937D01*
G01X698228Y475592D02*
X701969D01*
G01X686417Y471655D02*
X662795D01*
G01X690354Y467718D02*
G03X686417Y471655I-3937J0D01*
G01X701969Y577954D02*
G03Y585828I0J3937D01*
G01X698228D02*
Y610238D01*
G01X701969Y585828D02*
X698228D01*
G01X686319Y558269D02*
G03X674902I-5708J0D01*
G01D02*
G03X686319I5708J0D01*
G01X717106D02*
G03X707106I-5000J0D01*
G01D02*
G03X717106I5000J0D01*
G01X690354Y581891D02*
Y602364D01*
G01Y581891D02*
G03X694291Y577954I3937J0D01*
G01X724409D02*
X694291D01*
G01X701969Y610238D02*
G03Y618112I0J3937D01*
G01X698228Y610238D02*
X701969D01*
G01X686417Y606301D02*
X662795D01*
G01X690354Y602364D02*
G03X686417Y606301I-3937J0D01*
G01X674902Y692915D02*
G03X686319I5708J0D01*
G01X707106D02*
G03X717106I5000J0D01*
G01X701969Y712600D02*
G03Y720474I0J3937D01*
G01X698228D02*
Y744884D01*
G01X701969Y720474D02*
X698228D01*
G01X686319Y692915D02*
G03X674902I-5708J0D01*
G01X717106D02*
G03X707106I-5000J0D01*
G01X690354Y737010D02*
G03X686417Y740947I-3937J0D01*
G01X690354Y716537D02*
Y737010D01*
G01Y716538D02*
G03X694291Y712601I3937J0D01*
G01X724409Y712600D02*
X694291D01*
G01X701969Y744884D02*
G03Y752758I0J3937D01*
G01X698228Y744884D02*
X701969D01*
G01X686417Y740947D02*
X662795D01*
G01X686319Y827561D02*
G03X674902I-5708J0D01*
G01D02*
G03X686319I5708J0D01*
G01X717106D02*
G03X707106I-5000J0D01*
G01D02*
G03X717106I5000J0D01*
G01X701969Y847246D02*
G03Y855120I0J3937D01*
G01Y879530D02*
G03Y887404I0J3937D01*
G01X698228Y879530D02*
X701969D01*
G01X698228Y855120D02*
Y879530D01*
G01X701969Y855120D02*
X698228D01*
G01X686417Y875593D02*
X662795D01*
G01X690354Y871656D02*
G03X686417Y875593I-3937J0D01*
G01X690354Y851183D02*
Y871656D01*
G01Y851184D02*
G03X694291Y847247I3937J0D01*
G01X724409Y847246D02*
X694291D01*
G01X736220Y0D02*
G03X740157Y-3937I3937J0D01*
G01X736220Y5118D02*
Y0D01*
G01X740157Y-3937D02*
X793111D01*
G01X736220Y5118D02*
G03X728346I-3937J0D01*
G01X724409Y-3937D02*
G03X728346Y0I0J3937D01*
G01D02*
Y35433D01*
G01X720079Y47244D02*
G03Y39370I0J-3937D01*
G01Y79528D02*
G03Y71654I0J-3937D01*
G01X723820D02*
Y47244D01*
G01X720079Y71654D02*
X723820D01*
G01Y47244D02*
X720079D01*
G01X740157Y43307D02*
G03X736220Y39370I0J-3937D01*
G01X740157Y43307D02*
X759253D01*
G01X736220Y30315D02*
Y39370D01*
G01X735631Y51181D02*
X759253D01*
G01X731694Y55118D02*
G03X735631Y51181I3937J0D01*
G01X731694Y75591D02*
Y55118D01*
G01X728346Y30315D02*
G03X736220I3937J0D01*
G01X728346Y35433D02*
G03X724409Y39370I-3937J0D01*
G01X747540Y99213D02*
G03X758957I5708J0D01*
G01D02*
G03X747540I-5709J0D01*
G01X731694Y75591D02*
G03X727757Y79528I-3937J0D01*
G01X736220Y134646D02*
G03X740157Y130709I3937J0D01*
G01X771064D02*
X740157D01*
G01X736220Y139764D02*
Y134646D01*
G01X728346Y164961D02*
G03X736220I3937J0D01*
G01Y139764D02*
G03X728346I-3937J0D01*
G01X724409Y130709D02*
G03X728346Y134646I0J3937D01*
G01X736220Y164961D02*
Y174016D01*
G01X728346Y134646D02*
Y170079D01*
G01X720079Y181890D02*
G03Y174016I0J-3937D01*
G01Y214174D02*
G03Y206300I0J-3937D01*
G01X723820D02*
Y181890D01*
G01X720079Y206300D02*
X723820D01*
G01Y181890D02*
X720079D01*
G01X740157Y177953D02*
G03X736220Y174016I0J-3937D01*
G01X740157Y177953D02*
X759253D01*
G01X735631Y185827D02*
X759253D01*
G01X731694Y189764D02*
G03X735631Y185827I3937J0D01*
G01X731694Y210237D02*
Y189764D01*
G01Y210237D02*
G03X727757Y214174I-3937J0D01*
G01X728346Y170079D02*
G03X724409Y174016I-3937J0D01*
G01X747540Y233859D02*
G03X758957I5708J0D01*
G01D02*
G03X747540I-5709J0D01*
G01X720079Y316536D02*
G03Y308662I0J-3937D01*
G01X736220Y269292D02*
G03X740157Y265355I3937J0D01*
G01Y312599D02*
G03X736220Y308662I0J-3937D01*
G01X771064Y265355D02*
X740157D01*
G01X736220Y274410D02*
Y269292D01*
G01X728346Y299607D02*
G03X736220I3937J0D01*
G01Y274410D02*
G03X728346I-3937J0D01*
G01X736220Y299607D02*
Y308662D01*
G01X724409Y265355D02*
G03X728346Y269292I0J3937D01*
G01Y304725D02*
G03X724409Y308662I-3937J0D01*
G01X728346Y269292D02*
Y304725D01*
G01X720079Y348820D02*
G03Y340946I0J-3937D01*
G01X723820D02*
Y316536D01*
G01X720079Y340946D02*
X723820D01*
G01Y316536D02*
X720079D01*
G01X740157Y312599D02*
X759253D01*
G01X735631Y320473D02*
X759253D01*
G01X731694Y324410D02*
G03X735631Y320473I3937J0D01*
G01X731694Y344883D02*
Y324410D01*
G01Y344883D02*
G03X727757Y348820I-3937J0D01*
G01X736220Y403938D02*
G03X740157Y400001I3937J0D01*
G01X771064D02*
X740157D01*
G01X736220Y409056D02*
Y403938D01*
G01X724409Y400001D02*
G03X728346Y403938I0J3937D01*
G01D02*
Y439371D01*
G01X747540Y368505D02*
G03X758957I5708J0D01*
G01D02*
G03X747540I-5709J0D01*
G01X720079Y451182D02*
G03Y443308I0J-3937D01*
G01X723820Y475592D02*
Y451182D01*
G01D02*
X720079D01*
G01X740157Y447245D02*
G03X736220Y443308I0J-3937D01*
G01X740157Y447245D02*
X759253D01*
G01X728346Y434253D02*
G03X736220I3937J0D01*
G01Y409056D02*
G03X728346I-3937J0D01*
G01X736220Y434253D02*
Y443308D01*
G01X728346Y439371D02*
G03X724409Y443308I-3937J0D01*
G01X720079Y483466D02*
G03Y475592I0J-3937D01*
G01D02*
X723820D01*
G01X747540Y503151D02*
G03X758957I5708J0D01*
G01X735631Y455119D02*
X759253D01*
G01X731694Y459056D02*
G03X735631Y455119I3937J0D01*
G01X731694Y479529D02*
Y459056D01*
G01Y479529D02*
G03X727757Y483466I-3937J0D01*
G01X736220Y538584D02*
G03X740157Y534647I3937J0D01*
G01X771064D02*
X740157D01*
G01X736220Y543702D02*
Y538584D01*
G01Y543702D02*
G03X728346I-3937J0D01*
G01X724409Y534647D02*
G03X728346Y538584I0J3937D01*
G01D02*
Y574017D01*
G01X758957Y503151D02*
G03X747540I-5709J0D01*
G01X720079Y585828D02*
G03Y577954I0J-3937D01*
G01X723820Y610238D02*
Y585828D01*
G01D02*
X720079D01*
G01X740157Y581891D02*
G03X736220Y577954I0J-3937D01*
G01X740157Y581891D02*
X759253D01*
G01X728346Y568899D02*
G03X736220I3937J0D01*
G01D02*
Y577954D01*
G01X735631Y589765D02*
X759253D01*
G01X731694Y593702D02*
G03X735631Y589765I3937J0D01*
G01X731694Y614175D02*
Y593702D01*
G01X728346Y574017D02*
G03X724409Y577954I-3937J0D01*
G01X720079Y618112D02*
G03Y610238I0J-3937D01*
G01D02*
X723820D01*
G01X747540Y637797D02*
G03X758957I5708J0D01*
G01D02*
G03X747540I-5709J0D01*
G01X731694Y614175D02*
G03X727757Y618112I-3937J0D01*
G01X736220Y673230D02*
G03X740157Y669293I3937J0D01*
G01X771064D02*
X740157D01*
G01X736220Y678348D02*
Y673230D01*
G01Y678348D02*
G03X728346I-3937J0D01*
G01X724409Y669293D02*
G03X728346Y673230I0J3937D01*
G01D02*
Y708663D01*
G01X720079Y720474D02*
G03Y712600I0J-3937D01*
G01X723820Y744884D02*
Y720474D01*
G01D02*
X720079D01*
G01X740157Y716537D02*
G03X736220Y712600I0J-3937D01*
G01X740157Y716537D02*
X759253D01*
G01X728346Y703545D02*
G03X736220I3937J0D01*
G01D02*
Y712600D01*
G01X735631Y724411D02*
X759253D01*
G01X731694Y728348D02*
G03X735631Y724411I3937J0D01*
G01X731694Y748821D02*
Y728348D01*
G01X728346Y708664D02*
G03X724409Y712601I-3937J0D01*
G01X720079Y752758D02*
G03Y744884I0J-3937D01*
G01D02*
X723820D01*
G01X747540Y772443D02*
G03X758957I5708J0D01*
G01D02*
G03X747540I-5709J0D01*
G01X731694Y748821D02*
G03X727757Y752758I-3937J0D01*
G01X736220Y807876D02*
G03X740157Y803939I3937J0D01*
G01X771064D02*
X740157D01*
G01X736220Y812995D02*
Y807876D01*
G01X728346Y838191D02*
G03X736220I3937J0D01*
G01Y812995D02*
G03X728346I-3937J0D01*
G01X724409Y803939D02*
G03X728346Y807876I0J3937D01*
G01D02*
Y843309D01*
G01X720079Y855120D02*
G03Y847246I0J-3937D01*
G01Y887404D02*
G03Y879530I0J-3937D01*
G01X723820D02*
Y855120D01*
G01X720079Y879530D02*
X723820D01*
G01Y855120D02*
X720079D01*
G01X740157Y851183D02*
G03X736220Y847246I0J-3937D01*
G01X740157Y851183D02*
X759253D01*
G01X736220Y838191D02*
Y847246D01*
G01X735631Y859057D02*
X759253D01*
G01X731694Y862994D02*
G03X735631Y859057I3937J0D01*
G01X731694Y883467D02*
Y862994D01*
G01X728346Y843310D02*
G03X724409Y847247I-3937J0D01*
G01X747540Y907089D02*
G03X758957I5708J0D01*
G01D02*
G03X747540I-5709J0D01*
G01X731694Y883467D02*
G03X727757Y887404I-3937J0D01*
G01X793111Y-3937D02*
G03X800985Y3937I0J7874D01*
G01Y67717D02*
Y3937D01*
G01X789036Y19685D02*
G03I-4291J0D01*
G01X800985Y67717D02*
G03X797048Y71654I-3937J0D01*
G01X771064Y55118D02*
Y71654D01*
G01X796261D02*
X797048D01*
G01X759253Y43307D02*
G03X771064Y55118I0J11811D01*
G01X763190D02*
Y75591D01*
G01X759253Y51181D02*
G03X763190Y55118I0J3937D01*
G01X796261Y79528D02*
G03Y71654I0J-3937D01*
G01X771064D02*
G03Y79528I0J3937D01*
G01X779706Y99213D02*
G03X789784I5039J0D01*
G01D02*
G03X779706I-5039J0D01*
G01X800985Y118898D02*
G03X797048Y122835I-3937J0D01*
G01X800985Y83465D02*
Y118898D01*
G01X797048Y79528D02*
G03X800985Y83465I0J3937D01*
G01X767127Y79528D02*
X797048D01*
G01X767127D02*
G03X763190Y75591I0J-3937D01*
G01X797048Y130709D02*
G03X800985Y134646I0J3937D01*
G01X796261Y130709D02*
X797048D01*
G01X800985Y202363D02*
Y134646D01*
G01X789036Y154331D02*
G03I-4291J0D01*
G01X771064Y122835D02*
G03Y130709I0J3937D01*
G01X796261D02*
G03Y122835I0J-3937D01*
G01X800985Y202363D02*
G03X797048Y206300I-3937J0D01*
G01Y214174D02*
G03X800985Y218111I0J3937D01*
G01X796261Y206300D02*
X797048D01*
G01X767127Y214174D02*
X797048D01*
G01X767127D02*
G03X763190Y210237I0J-3937D01*
G01X771064Y189764D02*
Y206300D01*
G01X763190Y189764D02*
Y210237D01*
G01X759253Y177953D02*
G03X771064Y189764I0J11811D01*
G01X759253Y185827D02*
G03X763190Y189764I0J3937D01*
G01X796261Y214174D02*
G03Y206300I0J-3937D01*
G01X771064D02*
G03Y214174I0J3937D01*
G01Y257481D02*
G03Y265355I0J3937D01*
G01X796261D02*
G03Y257481I0J-3937D01*
G01X779706Y233859D02*
G03X789784I5039J0D01*
G01D02*
G03X779706I-5039J0D01*
G01X800985Y253544D02*
G03X797048Y257481I-3937J0D01*
G01X800985Y218111D02*
Y253544D01*
G01X797048Y265355D02*
G03X800985Y269292I0J3937D01*
G01X796261Y265355D02*
X797048D01*
G01X800985Y337009D02*
Y269292D01*
G01X789036Y288977D02*
G03I-4291J0D01*
G01X800985Y337009D02*
G03X797048Y340946I-3937J0D01*
G01X796261D02*
X797048D01*
G01X771064Y324410D02*
Y340946D01*
G01X759253Y312599D02*
G03X771064Y324410I0J11811D01*
G01X796261Y348820D02*
G03Y340946I0J-3937D01*
G01X771064D02*
G03Y348820I0J3937D01*
G01X800985Y352757D02*
Y388190D01*
G01X797048Y348820D02*
G03X800985Y352757I0J3937D01*
G01X767127Y348820D02*
X797048D01*
G01X767127D02*
G03X763190Y344883I0J-3937D01*
G01Y324410D02*
Y344883D01*
G01X759253Y320473D02*
G03X763190Y324410I0J3937D01*
G01X797048Y400001D02*
G03X800985Y403938I0J3937D01*
G01X796261Y400001D02*
X797048D01*
G01X800985Y471655D02*
Y403938D01*
G01X771064Y392127D02*
G03Y400001I0J3937D01*
G01X796261D02*
G03Y392127I0J-3937D01*
G01X779706Y368505D02*
G03X789784I5039J0D01*
G01D02*
G03X779706I-5039J0D01*
G01X800985Y388190D02*
G03X797048Y392127I-3937J0D01*
G01X759253Y447246D02*
G03X771064Y459057I0J11811D01*
G01X789036Y423623D02*
G03I-4291J0D01*
G01X800985Y471655D02*
G03X797048Y475592I-3937J0D01*
G01X796261D02*
X797048D01*
G01X771064Y459056D02*
Y475592D01*
G01X796261Y483466D02*
G03Y475592I0J-3937D01*
G01X771064D02*
G03Y483466I0J3937D01*
G01X779706Y503151D02*
G03X789784I5039J0D01*
G01X800985Y487403D02*
Y522836D01*
G01X797048Y483466D02*
G03X800985Y487403I0J3937D01*
G01X767127Y483466D02*
X797048D01*
G01X767127D02*
G03X763190Y479529I0J-3937D01*
G01Y459056D02*
Y479529D01*
G01X759253Y455120D02*
G03X763190Y459057I0J3937D01*
G01X797048Y534647D02*
G03X800985Y538584I0J3937D01*
G01X796261Y534647D02*
X797048D01*
G01X800985Y606301D02*
Y538584D01*
G01X771064Y526773D02*
G03Y534647I0J3937D01*
G01X796261D02*
G03Y526773I0J-3937D01*
G01X789784Y503151D02*
G03X779706I-5039J0D01*
G01X800985Y522836D02*
G03X797048Y526773I-3937J0D01*
G01X771064Y593702D02*
Y610238D01*
G01X759253Y581892D02*
G03X771064Y593703I0J11811D01*
G01X789036Y558269D02*
G03I-4291J0D01*
G01X763190Y593702D02*
Y614175D01*
G01X759253Y589766D02*
G03X763190Y593703I0J3937D01*
G01X800985Y606301D02*
G03X797048Y610238I-3937J0D01*
G01X796261D02*
X797048D01*
G01X796261Y618112D02*
G03Y610238I0J-3937D01*
G01X771064D02*
G03Y618112I0J3937D01*
G01X779706Y637797D02*
G03X789784I5039J0D01*
G01D02*
G03X779706I-5039J0D01*
G01X800985Y622049D02*
Y657482D01*
G01X797048Y618112D02*
G03X800985Y622049I0J3937D01*
G01X767127Y618112D02*
X797048D01*
G01X767127D02*
G03X763190Y614175I0J-3937D01*
G01X797048Y669293D02*
G03X800985Y673230I0J3937D01*
G01X796261Y669293D02*
X797048D01*
G01X800985Y740947D02*
Y673230D01*
G01X789036Y692915D02*
G03I-4291J0D01*
G01X771064Y661419D02*
G03Y669293I0J3937D01*
G01X796261D02*
G03Y661419I0J-3937D01*
G01X800985Y657482D02*
G03X797048Y661419I-3937J0D01*
G01X771064Y728348D02*
Y744884D01*
G01X759253Y716538D02*
G03X771064Y728349I0J11811D01*
G01X763190Y728348D02*
Y748821D01*
G01X759253Y724412D02*
G03X763190Y728349I0J3937D01*
G01X800985Y740947D02*
G03X797048Y744884I-3937J0D01*
G01X796261D02*
X797048D01*
G01X796261Y752758D02*
G03Y744884I0J-3937D01*
G01X771064D02*
G03Y752758I0J3937D01*
G01X779706Y772443D02*
G03X789784I5039J0D01*
G01D02*
G03X779706I-5039J0D01*
G01X800985Y756695D02*
Y792128D01*
G01X797048Y752758D02*
G03X800985Y756695I0J3937D01*
G01X767127Y752758D02*
X797048D01*
G01X767127D02*
G03X763190Y748821I0J-3937D01*
G01X800985Y855100D02*
Y807876D01*
G01X797048Y803939D02*
G03X800985Y807876I0J3937D01*
G01X796261Y803939D02*
X797048D01*
G01X789036Y827561D02*
G03I-4291J0D01*
G01X771064Y796065D02*
G03Y803939I0J3937D01*
G01X796261D02*
G03Y796065I0J-3937D01*
G01X800985Y792128D02*
G03X797048Y796065I-3937J0D01*
G01X800985Y862974D02*
G03Y855100I0J-3937D01*
G01Y875593D02*
G03X797048Y879530I-3937J0D01*
G01X800985Y875593D02*
Y862974D01*
G01X796261Y879530D02*
X797048D01*
G01X771064Y862994D02*
Y879530D01*
G01X759253Y851184D02*
G03X771064Y862995I0J11811D01*
G01X796261Y887404D02*
G03Y879530I0J-3937D01*
G01X771064D02*
G03Y887404I0J3937D01*
G01X763190Y862994D02*
Y883467D01*
G01X759253Y859058D02*
G03X763190Y862995I0J3937D01*
G01X779706Y907089D02*
G03X789784I5039J0D01*
G01D02*
G03X779706I-5039J0D01*
G01X800985Y926774D02*
G03X797048Y930711I-3937J0D01*
G01X800985Y891341D02*
Y926774D01*
G01X797048Y887404D02*
G03X800985Y891341I0J3937D01*
G01X767127Y887404D02*
X797048D01*
G01X767127D02*
G03X763190Y883467I0J-3937D01*
M02*
